G04 ================== begin FILE IDENTIFICATION RECORD ==================*
G04 Layout Name:  15669-1.brd*
G04 Film Name:    SE_REF_L1*
G04 File Format:  Gerber RS274X*
G04 File Origin:  Cadence Allegro 16.5-S056*
G04 Origin Date:  Wed Nov 16 04:09:10 2016*
G04 *
G04 Layer:  BOARD GEOMETRY/SE_REF_L1_TBL*
G04 Layer:  BOARD GEOMETRY/SE_REF_L1_TOP*
G04 Layer:  BOARD GEOMETRY/PANEL_OUTLINE*
G04 *
G04 Offset:    (0.00 0.00)*
G04 Mirror:    No*
G04 Mode:      Positive*
G04 Rotation:  0*
G04 FullContactRelief:  No*
G04 UndefLineWidth:     6.00*
G04 ================== end FILE IDENTIFICATION RECORD ====================*
%FSLAX35Y35*MOIN*%
%IR0*IPPOS*OFA0.00000B0.00000*MIA0B0*SFA1.00000B1.00000*%
%ADD10C,.02*%
%ADD11C,.006*%
%ADD12C,.00675*%
G75*
%LPD*%
G75*
G54D10*
G01X1178253Y1923126D02*
X1895753D01*
G01X1178253Y1888476D02*
X1895753D01*
G01X1178253Y1957776D02*
Y1888476D01*
G01Y1957776D02*
X1895753D01*
G01X1353253D02*
Y1888476D01*
G01X1580753Y1957776D02*
Y1888476D01*
G01X1685753Y1957776D02*
Y1888476D01*
G01X1895753Y1957776D02*
Y1888476D01*
G54D11*
G01X-84302Y-32800D02*
Y-50300D01*
G01X-89324Y-32800D02*
X-79280D01*
G01X-70514Y-50300D02*
Y-32800D01*
G01Y-41258D02*
X-69422Y-39800D01*
X-68330Y-38925D01*
X-66584Y-38634D01*
X-65274Y-38925D01*
X-63745Y-40092D01*
X-63090Y-41842D01*
Y-50300D01*
G01X-49302Y-38634D02*
Y-50300D01*
G01Y-33967D02*
X-49739Y-33675D01*
Y-33092D01*
X-49302Y-32800D01*
X-48865Y-33092D01*
Y-33675D01*
X-49302Y-33967D01*
G01X-35077Y-48259D02*
X-33985Y-49425D01*
X-32457Y-50300D01*
X-31147D01*
X-29837Y-49717D01*
X-28964Y-48842D01*
X-28527Y-47676D01*
X-28745Y-45925D01*
X-29619Y-45050D01*
X-33549Y-43300D01*
X-34422Y-41258D01*
X-33985Y-39800D01*
X-33112Y-38925D01*
X-31802Y-38634D01*
X-30492Y-38925D01*
X-29182Y-39800D01*
G01X141Y-54675D02*
X1670Y-55842D01*
X3416Y-56133D01*
X4944Y-55842D01*
X6255Y-54384D01*
X7128Y-52342D01*
Y-38634D01*
G01Y-40967D02*
X6255Y-39800D01*
X4944Y-38925D01*
X3416Y-38634D01*
X1670Y-39217D01*
X578Y-40383D01*
X-296Y-42425D01*
X-732Y-44467D01*
X-514Y-46217D01*
X360Y-48259D01*
X1670Y-49717D01*
X3416Y-50300D01*
X4726Y-50008D01*
X6255Y-48842D01*
X7128Y-47676D01*
G01X17423Y-42425D02*
X24410D01*
X23755Y-40383D01*
X22663Y-39217D01*
X21135Y-38634D01*
X19606Y-38925D01*
X18296Y-39800D01*
X17423Y-41842D01*
X16986Y-43592D01*
Y-45342D01*
X17423Y-47092D01*
X18515Y-48842D01*
X19825Y-50008D01*
X21353Y-50300D01*
X22881Y-49717D01*
X24410Y-47967D01*
G01X35141Y-50300D02*
Y-38634D01*
G01Y-40967D02*
X36233Y-39800D01*
X37325Y-38925D01*
X38853Y-38634D01*
X39944Y-38925D01*
X41255Y-39800D01*
G01X51768Y-50300D02*
Y-32800D01*
G01Y-41550D02*
X52860Y-39800D01*
X54170Y-38925D01*
X55480Y-38634D01*
X57444Y-39217D01*
X58755Y-40383D01*
X59628Y-42425D01*
Y-44758D01*
X59191Y-47092D01*
X58318Y-48842D01*
X56790Y-50008D01*
X55480Y-50300D01*
X54170Y-50008D01*
X52860Y-49134D01*
X51768Y-47676D01*
G01X69923Y-42425D02*
X76910D01*
X76255Y-40383D01*
X75163Y-39217D01*
X73635Y-38634D01*
X72106Y-38925D01*
X70796Y-39800D01*
X69923Y-41842D01*
X69486Y-43592D01*
Y-45342D01*
X69923Y-47092D01*
X71015Y-48842D01*
X72325Y-50008D01*
X73853Y-50300D01*
X75381Y-49717D01*
X76910Y-47967D01*
G01X87641Y-50300D02*
Y-38634D01*
G01Y-40967D02*
X88733Y-39800D01*
X89825Y-38925D01*
X91353Y-38634D01*
X92444Y-38925D01*
X93755Y-39800D01*
G01X125698Y-38634D02*
Y-50300D01*
G01Y-33967D02*
X125261Y-33675D01*
Y-33092D01*
X125698Y-32800D01*
X126135Y-33092D01*
Y-33675D01*
X125698Y-33967D01*
G01X139923Y-48259D02*
X141015Y-49425D01*
X142543Y-50300D01*
X143853D01*
X145163Y-49717D01*
X146036Y-48842D01*
X146473Y-47676D01*
X146255Y-45925D01*
X145381Y-45050D01*
X141451Y-43300D01*
X140578Y-41258D01*
X141015Y-39800D01*
X141888Y-38925D01*
X143198Y-38634D01*
X144508Y-38925D01*
X145818Y-39800D01*
G01X174704Y-54675D02*
X176233Y-55842D01*
X177543Y-56133D01*
X179290Y-55550D01*
X180600Y-54092D01*
X181255Y-51466D01*
Y-38634D01*
G01Y-33967D02*
X180818Y-33675D01*
Y-33092D01*
X181255Y-32800D01*
X181691Y-33092D01*
Y-33675D01*
X181255Y-33967D01*
G01X191986Y-38634D02*
Y-46800D01*
X192860Y-48842D01*
X194170Y-50008D01*
X195698Y-50300D01*
X197226Y-50008D01*
X198536Y-48842D01*
X199410Y-46800D01*
G01Y-50300D02*
Y-38634D01*
G01X209923Y-48259D02*
X211015Y-49425D01*
X212543Y-50300D01*
X213853D01*
X215163Y-49717D01*
X216036Y-48842D01*
X216473Y-47676D01*
X216255Y-45925D01*
X215381Y-45050D01*
X211451Y-43300D01*
X210578Y-41258D01*
X211015Y-39800D01*
X211888Y-38925D01*
X213198Y-38634D01*
X214508Y-38925D01*
X215818Y-39800D01*
G01X230698Y-32800D02*
Y-50300D01*
G01X227641Y-38634D02*
X233755D01*
G01X264388Y-50300D02*
Y-35425D01*
X264825Y-33967D01*
X265698Y-33092D01*
X267008Y-32800D01*
X268318Y-33383D01*
X268973Y-34842D01*
G01X266353Y-39800D02*
X261986D01*
G01X283198Y-50300D02*
X281888Y-50008D01*
X280578Y-48842D01*
X279704Y-46800D01*
X279268Y-44467D01*
X279704Y-42133D01*
X280578Y-40092D01*
X281888Y-38925D01*
X283198Y-38634D01*
X284508Y-38925D01*
X285818Y-40092D01*
X286691Y-42133D01*
X286910Y-44467D01*
X286691Y-46800D01*
X285818Y-48842D01*
X284508Y-50008D01*
X283198Y-50300D01*
G01X297641D02*
Y-38634D01*
G01Y-40967D02*
X298733Y-39800D01*
X299825Y-38925D01*
X301353Y-38634D01*
X302444Y-38925D01*
X303755Y-39800D01*
G01X331113Y-55550D02*
X332423Y-56133D01*
X334170Y-55550D01*
X335261Y-54384D01*
X336135Y-52925D01*
X337444Y-48259D01*
X340283Y-38634D01*
G01X333296D02*
X337444Y-48259D01*
G01X353198Y-50300D02*
X351888Y-50008D01*
X350578Y-48842D01*
X349704Y-46800D01*
X349268Y-44467D01*
X349704Y-42133D01*
X350578Y-40092D01*
X351888Y-38925D01*
X353198Y-38634D01*
X354508Y-38925D01*
X355818Y-40092D01*
X356691Y-42133D01*
X356910Y-44467D01*
X356691Y-46800D01*
X355818Y-48842D01*
X354508Y-50008D01*
X353198Y-50300D01*
G01X366986Y-38634D02*
Y-46800D01*
X367860Y-48842D01*
X369170Y-50008D01*
X370698Y-50300D01*
X372226Y-50008D01*
X373536Y-48842D01*
X374410Y-46800D01*
G01Y-50300D02*
Y-38634D01*
G01X385141Y-50300D02*
Y-38634D01*
G01Y-40967D02*
X386233Y-39800D01*
X387325Y-38925D01*
X388853Y-38634D01*
X389944Y-38925D01*
X391255Y-39800D01*
G01X420141Y-50300D02*
Y-38634D01*
G01Y-40967D02*
X421233Y-39800D01*
X422325Y-38925D01*
X423853Y-38634D01*
X424944Y-38925D01*
X426255Y-39800D01*
G01X437423Y-42425D02*
X444410D01*
X443755Y-40383D01*
X442663Y-39217D01*
X441135Y-38634D01*
X439606Y-38925D01*
X438296Y-39800D01*
X437423Y-41842D01*
X436986Y-43592D01*
Y-45342D01*
X437423Y-47092D01*
X438515Y-48842D01*
X439825Y-50008D01*
X441353Y-50300D01*
X442881Y-49717D01*
X444410Y-47967D01*
G01X456888Y-50300D02*
Y-35425D01*
X457325Y-33967D01*
X458198Y-33092D01*
X459508Y-32800D01*
X460818Y-33383D01*
X461473Y-34842D01*
G01X458853Y-39800D02*
X454486D01*
G01X472423Y-42425D02*
X479410D01*
X478755Y-40383D01*
X477663Y-39217D01*
X476135Y-38634D01*
X474606Y-38925D01*
X473296Y-39800D01*
X472423Y-41842D01*
X471986Y-43592D01*
Y-45342D01*
X472423Y-47092D01*
X473515Y-48842D01*
X474825Y-50008D01*
X476353Y-50300D01*
X477881Y-49717D01*
X479410Y-47967D01*
G01X490141Y-50300D02*
Y-38634D01*
G01Y-40967D02*
X491233Y-39800D01*
X492325Y-38925D01*
X493853Y-38634D01*
X494944Y-38925D01*
X496255Y-39800D01*
G01X507423Y-42425D02*
X514410D01*
X513755Y-40383D01*
X512663Y-39217D01*
X511135Y-38634D01*
X509606Y-38925D01*
X508296Y-39800D01*
X507423Y-41842D01*
X506986Y-43592D01*
Y-45342D01*
X507423Y-47092D01*
X508515Y-48842D01*
X509825Y-50008D01*
X511353Y-50300D01*
X512881Y-49717D01*
X514410Y-47967D01*
G01X524486Y-50300D02*
Y-38634D01*
G01Y-41550D02*
X525360Y-40092D01*
X526670Y-38925D01*
X528416Y-38634D01*
X529944Y-38925D01*
X531255Y-40092D01*
X531910Y-42133D01*
Y-50300D01*
G01X549191Y-40092D02*
X547663Y-38925D01*
X546353Y-38634D01*
X544606Y-39217D01*
X543296Y-40383D01*
X542423Y-42425D01*
X542204Y-44467D01*
X542423Y-46509D01*
X543296Y-48259D01*
X544606Y-49717D01*
X546353Y-50300D01*
X547881Y-49717D01*
X549191Y-48550D01*
G01X559923Y-42425D02*
X566910D01*
X566255Y-40383D01*
X565163Y-39217D01*
X563635Y-38634D01*
X562106Y-38925D01*
X560796Y-39800D01*
X559923Y-41842D01*
X559486Y-43592D01*
Y-45342D01*
X559923Y-47092D01*
X561015Y-48842D01*
X562325Y-50008D01*
X563853Y-50300D01*
X565381Y-49717D01*
X566910Y-47967D01*
G01X598198Y-32800D02*
Y-50300D01*
G01X595141Y-38634D02*
X601255D01*
G01X615698Y-50300D02*
X614388Y-50008D01*
X613078Y-48842D01*
X612204Y-46800D01*
X611768Y-44467D01*
X612204Y-42133D01*
X613078Y-40092D01*
X614388Y-38925D01*
X615698Y-38634D01*
X617008Y-38925D01*
X618318Y-40092D01*
X619191Y-42133D01*
X619410Y-44467D01*
X619191Y-46800D01*
X618318Y-48842D01*
X617008Y-50008D01*
X615698Y-50300D01*
G01X649388D02*
Y-35425D01*
X649825Y-33967D01*
X650698Y-33092D01*
X652008Y-32800D01*
X653318Y-33383D01*
X653973Y-34842D01*
G01X651353Y-39800D02*
X646986D01*
G01X668198Y-38634D02*
Y-50300D01*
G01Y-33967D02*
X667761Y-33675D01*
Y-33092D01*
X668198Y-32800D01*
X668635Y-33092D01*
Y-33675D01*
X668198Y-33967D01*
G01X681986Y-50300D02*
Y-38634D01*
G01Y-41550D02*
X682860Y-40092D01*
X684170Y-38925D01*
X685916Y-38634D01*
X687444Y-38925D01*
X688755Y-40092D01*
X689410Y-42133D01*
Y-50300D01*
G01X707128Y-32800D02*
Y-50300D01*
G01Y-47676D02*
X706255Y-49134D01*
X704944Y-50008D01*
X703416Y-50300D01*
X701670Y-49717D01*
X700360Y-48259D01*
X699486Y-46509D01*
X699268Y-44467D01*
X699486Y-42425D01*
X700360Y-40675D01*
X701670Y-39217D01*
X703416Y-38634D01*
X704944Y-38925D01*
X706036Y-39509D01*
X707128Y-40675D01*
G01X738198Y-32800D02*
Y-50300D01*
G01X735141Y-38634D02*
X741255D01*
G01X751986Y-50300D02*
Y-32800D01*
G01Y-41258D02*
X753078Y-39800D01*
X754170Y-38925D01*
X755916Y-38634D01*
X757226Y-38925D01*
X758755Y-40092D01*
X759410Y-41842D01*
Y-50300D01*
G01X769923Y-42425D02*
X776910D01*
X776255Y-40383D01*
X775163Y-39217D01*
X773635Y-38634D01*
X772106Y-38925D01*
X770796Y-39800D01*
X769923Y-41842D01*
X769486Y-43592D01*
Y-45342D01*
X769923Y-47092D01*
X771015Y-48842D01*
X772325Y-50008D01*
X773853Y-50300D01*
X775381Y-49717D01*
X776910Y-47967D01*
G01X803613D02*
X805360Y-49425D01*
X807325Y-50300D01*
X809071D01*
X810818Y-49425D01*
X812128Y-47967D01*
X812783Y-45925D01*
X812346Y-43884D01*
X811255Y-42133D01*
X809290Y-40967D01*
X806670Y-40383D01*
X805141Y-39217D01*
X804486Y-37175D01*
X804923Y-35133D01*
X806015Y-33675D01*
X807543Y-32800D01*
X809071D01*
X810600Y-33383D01*
X811910Y-34842D01*
G01X830065Y-50300D02*
X821331D01*
Y-32800D01*
X830065D01*
G01X826571Y-41258D02*
X821331D01*
G01X860698Y-38634D02*
Y-50300D01*
G01Y-33967D02*
X860261Y-33675D01*
Y-33092D01*
X860698Y-32800D01*
X861135Y-33092D01*
Y-33675D01*
X860698Y-33967D01*
G01X871648Y-50300D02*
Y-38634D01*
G01Y-41842D02*
X872303Y-40383D01*
X873395Y-39217D01*
X874923Y-38634D01*
X876451Y-39217D01*
X877543Y-40383D01*
X878198Y-41842D01*
Y-50300D01*
G01Y-41842D02*
X878853Y-40383D01*
X879944Y-39217D01*
X881473Y-38634D01*
X883001Y-39217D01*
X884093Y-40383D01*
X884748Y-42133D01*
Y-50300D01*
G01X891768Y-56133D02*
Y-38634D01*
G01Y-41258D02*
X892860Y-39800D01*
X893951Y-38925D01*
X895698Y-38634D01*
X897226Y-38925D01*
X898755Y-40383D01*
X899410Y-42425D01*
X899628Y-44467D01*
X899410Y-46509D01*
X898755Y-48550D01*
X897444Y-49717D01*
X895698Y-50300D01*
X894170Y-50008D01*
X892641Y-49134D01*
X891768Y-47967D01*
G01X909923Y-42425D02*
X916910D01*
X916255Y-40383D01*
X915163Y-39217D01*
X913635Y-38634D01*
X912106Y-38925D01*
X910796Y-39800D01*
X909923Y-41842D01*
X909486Y-43592D01*
Y-45342D01*
X909923Y-47092D01*
X911015Y-48842D01*
X912325Y-50008D01*
X913853Y-50300D01*
X915381Y-49717D01*
X916910Y-47967D01*
G01X934628Y-32800D02*
Y-50300D01*
G01Y-47676D02*
X933755Y-49134D01*
X932444Y-50008D01*
X930916Y-50300D01*
X929170Y-49717D01*
X927860Y-48259D01*
X926986Y-46509D01*
X926768Y-44467D01*
X926986Y-42425D01*
X927860Y-40675D01*
X929170Y-39217D01*
X930916Y-38634D01*
X932444Y-38925D01*
X933536Y-39509D01*
X934628Y-40675D01*
G01X952128Y-50300D02*
Y-38634D01*
G01Y-40675D02*
X951255Y-39509D01*
X949944Y-38925D01*
X948416Y-38634D01*
X946888Y-39217D01*
X945578Y-40383D01*
X944704Y-42133D01*
X944268Y-44467D01*
X944704Y-46800D01*
X945578Y-48550D01*
X946888Y-49717D01*
X948416Y-50300D01*
X949944Y-50008D01*
X951255Y-49134D01*
X952128Y-47967D01*
G01X961986Y-50300D02*
Y-38634D01*
G01Y-41550D02*
X962860Y-40092D01*
X964170Y-38925D01*
X965916Y-38634D01*
X967444Y-38925D01*
X968755Y-40092D01*
X969410Y-42133D01*
Y-50300D01*
G01X986691Y-40092D02*
X985163Y-38925D01*
X983853Y-38634D01*
X982106Y-39217D01*
X980796Y-40383D01*
X979923Y-42425D01*
X979704Y-44467D01*
X979923Y-46509D01*
X980796Y-48259D01*
X982106Y-49717D01*
X983853Y-50300D01*
X985381Y-49717D01*
X986691Y-48550D01*
G01X997423Y-42425D02*
X1004410D01*
X1003755Y-40383D01*
X1002663Y-39217D01*
X1001135Y-38634D01*
X999606Y-38925D01*
X998296Y-39800D01*
X997423Y-41842D01*
X996986Y-43592D01*
Y-45342D01*
X997423Y-47092D01*
X998515Y-48842D01*
X999825Y-50008D01*
X1001353Y-50300D01*
X1002881Y-49717D01*
X1004410Y-47967D01*
G01X1035698Y-32800D02*
Y-50300D01*
G01X1032641Y-38634D02*
X1038755D01*
G01X1050141Y-50300D02*
Y-38634D01*
G01Y-40967D02*
X1051233Y-39800D01*
X1052325Y-38925D01*
X1053853Y-38634D01*
X1054944Y-38925D01*
X1056255Y-39800D01*
G01X1074628Y-50300D02*
Y-38634D01*
G01Y-40675D02*
X1073755Y-39509D01*
X1072444Y-38925D01*
X1070916Y-38634D01*
X1069388Y-39217D01*
X1068078Y-40383D01*
X1067204Y-42133D01*
X1066768Y-44467D01*
X1067204Y-46800D01*
X1068078Y-48550D01*
X1069388Y-49717D01*
X1070916Y-50300D01*
X1072444Y-50008D01*
X1073755Y-49134D01*
X1074628Y-47967D01*
G01X1091691Y-40092D02*
X1090163Y-38925D01*
X1088853Y-38634D01*
X1087106Y-39217D01*
X1085796Y-40383D01*
X1084923Y-42425D01*
X1084704Y-44467D01*
X1084923Y-46509D01*
X1085796Y-48259D01*
X1087106Y-49717D01*
X1088853Y-50300D01*
X1090381Y-49717D01*
X1091691Y-48550D01*
G01X1102423Y-42425D02*
X1109410D01*
X1108755Y-40383D01*
X1107663Y-39217D01*
X1106135Y-38634D01*
X1104606Y-38925D01*
X1103296Y-39800D01*
X1102423Y-41842D01*
X1101986Y-43592D01*
Y-45342D01*
X1102423Y-47092D01*
X1103515Y-48842D01*
X1104825Y-50008D01*
X1106353Y-50300D01*
X1107881Y-49717D01*
X1109410Y-47967D01*
G01X1119923Y-48259D02*
X1121015Y-49425D01*
X1122543Y-50300D01*
X1123853D01*
X1125163Y-49717D01*
X1126036Y-48842D01*
X1126473Y-47676D01*
X1126255Y-45925D01*
X1125381Y-45050D01*
X1121451Y-43300D01*
X1120578Y-41258D01*
X1121015Y-39800D01*
X1121888Y-38925D01*
X1123198Y-38634D01*
X1124508Y-38925D01*
X1125818Y-39800D01*
G01X1158198Y-38634D02*
Y-50300D01*
G01Y-33967D02*
X1157761Y-33675D01*
Y-33092D01*
X1158198Y-32800D01*
X1158635Y-33092D01*
Y-33675D01*
X1158198Y-33967D01*
G01X1171986Y-50300D02*
Y-38634D01*
G01Y-41550D02*
X1172860Y-40092D01*
X1174170Y-38925D01*
X1175916Y-38634D01*
X1177444Y-38925D01*
X1178755Y-40092D01*
X1179410Y-42133D01*
Y-50300D01*
G01X1210698D02*
Y-32800D01*
G01X1232128Y-50300D02*
Y-38634D01*
G01Y-40675D02*
X1231255Y-39509D01*
X1229944Y-38925D01*
X1228416Y-38634D01*
X1226888Y-39217D01*
X1225578Y-40383D01*
X1224704Y-42133D01*
X1224268Y-44467D01*
X1224704Y-46800D01*
X1225578Y-48550D01*
X1226888Y-49717D01*
X1228416Y-50300D01*
X1229944Y-50008D01*
X1231255Y-49134D01*
X1232128Y-47967D01*
G01X1241113Y-55550D02*
X1242423Y-56133D01*
X1244170Y-55550D01*
X1245261Y-54384D01*
X1246135Y-52925D01*
X1247444Y-48259D01*
X1250283Y-38634D01*
G01X1243296D02*
X1247444Y-48259D01*
G01X1259923Y-42425D02*
X1266910D01*
X1266255Y-40383D01*
X1265163Y-39217D01*
X1263635Y-38634D01*
X1262106Y-38925D01*
X1260796Y-39800D01*
X1259923Y-41842D01*
X1259486Y-43592D01*
Y-45342D01*
X1259923Y-47092D01*
X1261015Y-48842D01*
X1262325Y-50008D01*
X1263853Y-50300D01*
X1265381Y-49717D01*
X1266910Y-47967D01*
G01X1277641Y-50300D02*
Y-38634D01*
G01Y-40967D02*
X1278733Y-39800D01*
X1279825Y-38925D01*
X1281353Y-38634D01*
X1282444Y-38925D01*
X1283755Y-39800D01*
G01X1311331Y-32800D02*
Y-50300D01*
X1320065D01*
G01X1333198D02*
Y-32800D01*
X1330578Y-36300D01*
G01Y-50300D02*
X1335818D01*
G01X1350698Y-50883D02*
X1350261Y-50592D01*
Y-50008D01*
X1350698Y-49717D01*
X1351135Y-50008D01*
Y-50592D01*
X1350698Y-50883D01*
G01X1201883Y1950376D02*
X1207123D01*
G01X1204503D02*
Y1932876D01*
G01X1201883D02*
X1207123D01*
G01X1216326D02*
Y1950376D01*
X1222003Y1935793D01*
X1227680Y1950376D01*
Y1932876D01*
G01X1235136D02*
Y1950376D01*
X1240376D01*
X1242123Y1949501D01*
X1243433Y1947459D01*
X1243870Y1945126D01*
X1243433Y1942793D01*
X1242341Y1941043D01*
X1240376Y1940167D01*
X1235136D01*
G01X1255911Y1927043D02*
X1253728Y1929959D01*
X1252636Y1932876D01*
Y1944542D01*
X1253728Y1947459D01*
X1255911Y1950376D01*
G01X1274503Y1932876D02*
X1272756Y1933168D01*
X1271228Y1934334D01*
X1269918Y1936084D01*
X1269044Y1938126D01*
X1268608Y1940459D01*
Y1942793D01*
X1269044Y1945126D01*
X1269918Y1947168D01*
X1271228Y1948917D01*
X1272756Y1950084D01*
X1274503Y1950376D01*
X1276249Y1950084D01*
X1277778Y1948917D01*
X1279088Y1947168D01*
X1279962Y1945126D01*
X1280398Y1942793D01*
Y1940459D01*
X1279962Y1938126D01*
X1279088Y1936084D01*
X1277778Y1934334D01*
X1276249Y1933168D01*
X1274503Y1932876D01*
G01X1288291D02*
Y1950376D01*
G01Y1941918D02*
X1289383Y1943376D01*
X1290475Y1944251D01*
X1292221Y1944542D01*
X1293531Y1944251D01*
X1295060Y1943084D01*
X1295715Y1941334D01*
Y1932876D01*
G01X1302953D02*
Y1944542D01*
G01Y1941334D02*
X1303608Y1942793D01*
X1304700Y1943959D01*
X1306228Y1944542D01*
X1307756Y1943959D01*
X1308848Y1942793D01*
X1309503Y1941334D01*
Y1932876D01*
G01Y1941334D02*
X1310158Y1942793D01*
X1311249Y1943959D01*
X1312778Y1944542D01*
X1314306Y1943959D01*
X1315398Y1942793D01*
X1316053Y1941043D01*
Y1932876D01*
G01X1328095Y1927043D02*
X1330278Y1929959D01*
X1331370Y1932876D01*
Y1944542D01*
X1330278Y1947459D01*
X1328095Y1950376D01*
G01X1180218Y1969859D02*
X1181965Y1968401D01*
X1183930Y1967526D01*
X1185676D01*
X1187423Y1968401D01*
X1188733Y1969859D01*
X1189388Y1971901D01*
X1188951Y1973942D01*
X1187860Y1975693D01*
X1185895Y1976859D01*
X1183275Y1977443D01*
X1181746Y1978609D01*
X1181091Y1980651D01*
X1181528Y1982693D01*
X1182620Y1984151D01*
X1184148Y1985026D01*
X1185676D01*
X1187205Y1984443D01*
X1188515Y1982984D01*
G01X1206670Y1967526D02*
X1197936D01*
Y1985026D01*
X1206670D01*
G01X1203176Y1976568D02*
X1197936D01*
G01X1234683Y1985026D02*
X1239923D01*
G01X1237303D02*
Y1967526D01*
G01X1234683D02*
X1239923D01*
G01X1249126D02*
Y1985026D01*
X1254803Y1970443D01*
X1260480Y1985026D01*
Y1967526D01*
G01X1267936D02*
Y1985026D01*
X1273176D01*
X1274923Y1984151D01*
X1276233Y1982109D01*
X1276670Y1979776D01*
X1276233Y1977443D01*
X1275141Y1975693D01*
X1273176Y1974817D01*
X1267936D01*
G01X1294170Y1967526D02*
X1285436D01*
Y1985026D01*
X1294170D01*
G01X1290676Y1976568D02*
X1285436D01*
G01X1302500Y1967526D02*
Y1985026D01*
X1306866D01*
X1308613Y1984151D01*
X1309923Y1982984D01*
X1311015Y1981235D01*
X1311888Y1979192D01*
X1312106Y1976276D01*
X1311888Y1973359D01*
X1311015Y1971317D01*
X1309923Y1969567D01*
X1308613Y1968401D01*
X1306866Y1967526D01*
X1302500D01*
G01X1319344D02*
X1324803Y1985026D01*
X1330262Y1967526D01*
G01X1328296Y1973651D02*
X1321309D01*
G01X1337281Y1967526D02*
Y1985026D01*
X1347325Y1967526D01*
Y1985026D01*
G01X1364606Y1983567D02*
X1363296Y1984443D01*
X1361768Y1985026D01*
X1360021D01*
X1358056Y1984151D01*
X1356528Y1982693D01*
X1355436Y1980942D01*
X1354563Y1978026D01*
X1354344Y1975401D01*
X1354781Y1972776D01*
X1355436Y1971026D01*
X1356746Y1969276D01*
X1358275Y1968109D01*
X1359803Y1967526D01*
X1361331D01*
X1362860Y1968109D01*
X1364170Y1968984D01*
X1365262Y1970150D01*
G01X1381670Y1967526D02*
X1372936D01*
Y1985026D01*
X1381670D01*
G01X1378176Y1976568D02*
X1372936D01*
G01X1412303Y1985026D02*
Y1967526D01*
G01X1407281Y1985026D02*
X1417325D01*
G01X1424344Y1967526D02*
X1429803Y1985026D01*
X1435262Y1967526D01*
G01X1433296Y1973651D02*
X1426309D01*
G01X1449049Y1976859D02*
X1449923Y1977734D01*
X1450578Y1979192D01*
X1451015Y1981235D01*
X1450578Y1982984D01*
X1449705Y1984151D01*
X1448176Y1985026D01*
X1442281D01*
Y1967526D01*
X1449486D01*
X1451015Y1968692D01*
X1451888Y1970443D01*
X1452325Y1972484D01*
X1451888Y1974526D01*
X1450578Y1976276D01*
X1449049Y1976859D01*
X1442281D01*
G01X1460436Y1985026D02*
Y1967526D01*
X1469170D01*
G01X1486670D02*
X1477936D01*
Y1985026D01*
X1486670D01*
G01X1483176Y1976568D02*
X1477936D01*
G01X1499803Y1966943D02*
X1499366Y1967234D01*
Y1967818D01*
X1499803Y1968109D01*
X1500240Y1967818D01*
Y1967234D01*
X1499803Y1966943D01*
G01Y1974817D02*
X1499366Y1975109D01*
Y1975693D01*
X1499803Y1975984D01*
X1500240Y1975693D01*
Y1975109D01*
X1499803Y1974817D01*
G01X1530436Y1985026D02*
Y1967526D01*
X1539170D01*
G01X1552303D02*
Y1985026D01*
X1549683Y1981526D01*
G01Y1967526D02*
X1554923D01*
G01X1234700Y1900850D02*
X1236009Y1899392D01*
X1237538Y1898518D01*
X1239503Y1898226D01*
X1241468Y1898809D01*
X1242996Y1899976D01*
X1244088Y1902017D01*
X1244306Y1904351D01*
X1243870Y1906684D01*
X1242778Y1908143D01*
X1241249Y1909309D01*
X1239721Y1909601D01*
X1238193Y1909309D01*
X1236228Y1908143D01*
X1236883Y1915726D01*
X1242778D01*
G01X1257003D02*
X1255256Y1915143D01*
X1253946Y1913684D01*
X1253073Y1911935D01*
X1252418Y1909601D01*
X1252200Y1906976D01*
X1252418Y1904351D01*
X1253073Y1902017D01*
X1253946Y1900267D01*
X1255256Y1898809D01*
X1257003Y1898226D01*
X1258749Y1898809D01*
X1260060Y1900267D01*
X1260933Y1902017D01*
X1261588Y1904351D01*
X1261806Y1906976D01*
X1261588Y1909601D01*
X1260933Y1911935D01*
X1260060Y1913684D01*
X1258749Y1915143D01*
X1257003Y1915726D01*
G01X1274503Y1897643D02*
X1274066Y1897934D01*
Y1898518D01*
X1274503Y1898809D01*
X1274940Y1898518D01*
Y1897934D01*
X1274503Y1897643D01*
G01X1292003Y1915726D02*
X1290256Y1915143D01*
X1288946Y1913684D01*
X1288073Y1911935D01*
X1287418Y1909601D01*
X1287200Y1906976D01*
X1287418Y1904351D01*
X1288073Y1902017D01*
X1288946Y1900267D01*
X1290256Y1898809D01*
X1292003Y1898226D01*
X1293749Y1898809D01*
X1295060Y1900267D01*
X1295933Y1902017D01*
X1296588Y1904351D01*
X1296806Y1906976D01*
X1296588Y1909601D01*
X1295933Y1911935D01*
X1295060Y1913684D01*
X1293749Y1915143D01*
X1292003Y1915726D01*
G01X1372953Y1950376D02*
X1376009Y1932876D01*
X1379503Y1950376D01*
X1382996Y1932876D01*
X1386053Y1950376D01*
G01X1394383D02*
X1399623D01*
G01X1397003D02*
Y1932876D01*
G01X1394383D02*
X1399623D01*
G01X1409700D02*
Y1950376D01*
X1414066D01*
X1415813Y1949501D01*
X1417123Y1948334D01*
X1418215Y1946585D01*
X1419088Y1944542D01*
X1419306Y1941626D01*
X1419088Y1938709D01*
X1418215Y1936667D01*
X1417123Y1934917D01*
X1415813Y1933751D01*
X1414066Y1932876D01*
X1409700D01*
G01X1432003Y1950376D02*
Y1932876D01*
G01X1426981Y1950376D02*
X1437025D01*
G01X1444918Y1932876D02*
Y1950376D01*
G01X1454088D02*
Y1932876D01*
G01Y1941626D02*
X1444918D01*
G01X1465911Y1927043D02*
X1463728Y1929959D01*
X1462636Y1932876D01*
Y1944542D01*
X1463728Y1947459D01*
X1465911Y1950376D01*
G01X1477953Y1932876D02*
Y1944542D01*
G01Y1941334D02*
X1478608Y1942793D01*
X1479700Y1943959D01*
X1481228Y1944542D01*
X1482756Y1943959D01*
X1483848Y1942793D01*
X1484503Y1941334D01*
Y1932876D01*
G01Y1941334D02*
X1485158Y1942793D01*
X1486249Y1943959D01*
X1487778Y1944542D01*
X1489306Y1943959D01*
X1490398Y1942793D01*
X1491053Y1941043D01*
Y1932876D01*
G01X1502003Y1944542D02*
Y1932876D01*
G01Y1949209D02*
X1501566Y1949501D01*
Y1950084D01*
X1502003Y1950376D01*
X1502440Y1950084D01*
Y1949501D01*
X1502003Y1949209D01*
G01X1519503Y1932876D02*
Y1950376D01*
G01X1533728Y1934917D02*
X1534820Y1933751D01*
X1536348Y1932876D01*
X1537658D01*
X1538968Y1933459D01*
X1539841Y1934334D01*
X1540278Y1935500D01*
X1540060Y1937251D01*
X1539186Y1938126D01*
X1535256Y1939876D01*
X1534383Y1941918D01*
X1534820Y1943376D01*
X1535693Y1944251D01*
X1537003Y1944542D01*
X1538313Y1944251D01*
X1539623Y1943376D01*
G01X1555595Y1927043D02*
X1557778Y1929959D01*
X1558870Y1932876D01*
Y1944542D01*
X1557778Y1947459D01*
X1555595Y1950376D01*
G01X1436605Y1905517D02*
X1438133Y1907559D01*
X1439443Y1908726D01*
X1441190Y1909309D01*
X1442718Y1908726D01*
X1443810Y1907559D01*
X1444683Y1905809D01*
X1444901Y1903768D01*
X1444683Y1902017D01*
X1443810Y1900267D01*
X1442499Y1898809D01*
X1440971Y1898226D01*
X1439225Y1898809D01*
X1437696Y1900559D01*
X1436823Y1903184D01*
X1436605Y1906101D01*
X1437041Y1909892D01*
X1437696Y1911935D01*
X1438788Y1913976D01*
X1440316Y1915434D01*
X1441845Y1915726D01*
X1443373Y1915143D01*
X1444465Y1913684D01*
G01X1458253Y1897643D02*
X1457816Y1897934D01*
Y1898518D01*
X1458253Y1898809D01*
X1458690Y1898518D01*
Y1897934D01*
X1458253Y1897643D01*
G01X1475316Y1898226D02*
X1475753Y1902017D01*
X1476408Y1905226D01*
X1477281Y1908143D01*
X1478373Y1911351D01*
X1480120Y1915726D01*
X1471386D01*
G01X1488450Y1900850D02*
X1489759Y1899392D01*
X1491288Y1898518D01*
X1493253Y1898226D01*
X1495218Y1898809D01*
X1496746Y1899976D01*
X1497838Y1902017D01*
X1498056Y1904351D01*
X1497620Y1906684D01*
X1496528Y1908143D01*
X1494999Y1909309D01*
X1493471Y1909601D01*
X1491943Y1909309D01*
X1489978Y1908143D01*
X1490633Y1915726D01*
X1496528D01*
G01X1607003Y1950376D02*
Y1932876D01*
G01X1601981Y1950376D02*
X1612025D01*
G01X1624503Y1932876D02*
Y1940751D01*
X1620136Y1950376D01*
G01X1628870D02*
X1624503Y1940751D01*
G01X1637636Y1932876D02*
Y1950376D01*
X1642876D01*
X1644623Y1949501D01*
X1645933Y1947459D01*
X1646370Y1945126D01*
X1645933Y1942793D01*
X1644841Y1941043D01*
X1642876Y1940167D01*
X1637636D01*
G01X1663870Y1932876D02*
X1655136D01*
Y1950376D01*
X1663870D01*
G01X1660376Y1941918D02*
X1655136D01*
G01X1619918Y1900559D02*
X1621665Y1899101D01*
X1623630Y1898226D01*
X1625376D01*
X1627123Y1899101D01*
X1628433Y1900559D01*
X1629088Y1902601D01*
X1628651Y1904642D01*
X1627560Y1906393D01*
X1625595Y1907559D01*
X1622975Y1908143D01*
X1621446Y1909309D01*
X1620791Y1911351D01*
X1621228Y1913393D01*
X1622320Y1914851D01*
X1623848Y1915726D01*
X1625376D01*
X1626905Y1915143D01*
X1628215Y1913684D01*
G01X1646370Y1898226D02*
X1637636D01*
Y1915726D01*
X1646370D01*
G01X1642876Y1907268D02*
X1637636D01*
G01X1707636Y1932876D02*
Y1950376D01*
X1713095D01*
X1714841Y1949501D01*
X1715933Y1948334D01*
X1716370Y1946001D01*
X1715933Y1943667D01*
X1714623Y1942209D01*
X1713095Y1941334D01*
X1707636D01*
G01X1713095D02*
X1716370Y1932876D01*
G01X1726228Y1940751D02*
X1733215D01*
X1732560Y1942793D01*
X1731468Y1943959D01*
X1729940Y1944542D01*
X1728411Y1944251D01*
X1727101Y1943376D01*
X1726228Y1941334D01*
X1725791Y1939584D01*
Y1937834D01*
X1726228Y1936084D01*
X1727320Y1934334D01*
X1728630Y1933168D01*
X1730158Y1932876D01*
X1731686Y1933459D01*
X1733215Y1935209D01*
G01X1745693Y1932876D02*
Y1947751D01*
X1746130Y1949209D01*
X1747003Y1950084D01*
X1748313Y1950376D01*
X1749623Y1949793D01*
X1750278Y1948334D01*
G01X1747658Y1943376D02*
X1743291D01*
G01X1764503Y1932293D02*
X1764066Y1932584D01*
Y1933168D01*
X1764503Y1933459D01*
X1764940Y1933168D01*
Y1932584D01*
X1764503Y1932293D01*
G01X1795136Y1932876D02*
Y1950376D01*
X1800376D01*
X1802123Y1949501D01*
X1803433Y1947459D01*
X1803870Y1945126D01*
X1803433Y1942793D01*
X1802341Y1941043D01*
X1800376Y1940167D01*
X1795136D01*
G01X1817003Y1932876D02*
Y1950376D01*
G01X1838433Y1932876D02*
Y1944542D01*
G01Y1942501D02*
X1837560Y1943667D01*
X1836249Y1944251D01*
X1834721Y1944542D01*
X1833193Y1943959D01*
X1831883Y1942793D01*
X1831009Y1941043D01*
X1830573Y1938709D01*
X1831009Y1936376D01*
X1831883Y1934626D01*
X1833193Y1933459D01*
X1834721Y1932876D01*
X1836249Y1933168D01*
X1837560Y1934042D01*
X1838433Y1935209D01*
G01X1848291Y1932876D02*
Y1944542D01*
G01Y1941626D02*
X1849165Y1943084D01*
X1850475Y1944251D01*
X1852221Y1944542D01*
X1853749Y1944251D01*
X1855060Y1943084D01*
X1855715Y1941043D01*
Y1932876D01*
G01X1866228Y1940751D02*
X1873215D01*
X1872560Y1942793D01*
X1871468Y1943959D01*
X1869940Y1944542D01*
X1868411Y1944251D01*
X1867101Y1943376D01*
X1866228Y1941334D01*
X1865791Y1939584D01*
Y1937834D01*
X1866228Y1936084D01*
X1867320Y1934334D01*
X1868630Y1933168D01*
X1870158Y1932876D01*
X1871686Y1933459D01*
X1873215Y1935209D01*
G01X1777636Y1915726D02*
Y1898226D01*
X1786370D01*
G01X1795355Y1912809D02*
X1796665Y1914559D01*
X1798193Y1915434D01*
X1799940Y1915726D01*
X1802123Y1915143D01*
X1803651Y1913684D01*
X1804088Y1911935D01*
X1803870Y1910184D01*
X1802996Y1908726D01*
X1798630Y1905809D01*
X1796665Y1903768D01*
X1795355Y1900850D01*
X1794918Y1898226D01*
X1804088D01*
G01X1912500Y1932293D02*
X1922106Y1945126D01*
G01X1917303Y1947459D02*
Y1929959D01*
G01X1922106Y1932293D02*
X1912500Y1945126D01*
G01X1910753Y1938709D02*
X1923853D01*
G01X1949465D02*
X1955141D01*
G01X1982500Y1932876D02*
Y1950376D01*
X1986866D01*
X1988613Y1949501D01*
X1989923Y1948334D01*
X1991015Y1946585D01*
X1991888Y1944542D01*
X1992106Y1941626D01*
X1991888Y1938709D01*
X1991015Y1936667D01*
X1989923Y1934917D01*
X1988613Y1933751D01*
X1986866Y1932876D01*
X1982500D01*
G01X2001528Y1940751D02*
X2008515D01*
X2007860Y1942793D01*
X2006768Y1943959D01*
X2005240Y1944542D01*
X2003711Y1944251D01*
X2002401Y1943376D01*
X2001528Y1941334D01*
X2001091Y1939584D01*
Y1937834D01*
X2001528Y1936084D01*
X2002620Y1934334D01*
X2003930Y1933168D01*
X2005458Y1932876D01*
X2006986Y1933459D01*
X2008515Y1935209D01*
G01X2018591Y1932876D02*
Y1944542D01*
G01Y1941626D02*
X2019465Y1943084D01*
X2020775Y1944251D01*
X2022521Y1944542D01*
X2024049Y1944251D01*
X2025360Y1943084D01*
X2026015Y1941043D01*
Y1932876D01*
G01X2039803D02*
X2038493Y1933168D01*
X2037183Y1934334D01*
X2036309Y1936376D01*
X2035873Y1938709D01*
X2036309Y1941043D01*
X2037183Y1943084D01*
X2038493Y1944251D01*
X2039803Y1944542D01*
X2041113Y1944251D01*
X2042423Y1943084D01*
X2043296Y1941043D01*
X2043515Y1938709D01*
X2043296Y1936376D01*
X2042423Y1934334D01*
X2041113Y1933168D01*
X2039803Y1932876D01*
G01X2057303Y1950376D02*
Y1932876D01*
G01X2054246Y1944542D02*
X2060360D01*
G01X2071528Y1940751D02*
X2078515D01*
X2077860Y1942793D01*
X2076768Y1943959D01*
X2075240Y1944542D01*
X2073711Y1944251D01*
X2072401Y1943376D01*
X2071528Y1941334D01*
X2071091Y1939584D01*
Y1937834D01*
X2071528Y1936084D01*
X2072620Y1934334D01*
X2073930Y1933168D01*
X2075458Y1932876D01*
X2076986Y1933459D01*
X2078515Y1935209D01*
G01X2089028Y1934917D02*
X2090120Y1933751D01*
X2091648Y1932876D01*
X2092958D01*
X2094268Y1933459D01*
X2095141Y1934334D01*
X2095578Y1935500D01*
X2095360Y1937251D01*
X2094486Y1938126D01*
X2090556Y1939876D01*
X2089683Y1941918D01*
X2090120Y1943376D01*
X2090993Y1944251D01*
X2092303Y1944542D01*
X2093613Y1944251D01*
X2094923Y1943376D01*
G01X2127303Y1950376D02*
Y1932876D01*
G01X2124246Y1944542D02*
X2130360D01*
G01X2141091Y1932876D02*
Y1950376D01*
G01Y1941918D02*
X2142183Y1943376D01*
X2143275Y1944251D01*
X2145021Y1944542D01*
X2146331Y1944251D01*
X2147860Y1943084D01*
X2148515Y1941334D01*
Y1932876D01*
G01X2166233D02*
Y1944542D01*
G01Y1942501D02*
X2165360Y1943667D01*
X2164049Y1944251D01*
X2162521Y1944542D01*
X2160993Y1943959D01*
X2159683Y1942793D01*
X2158809Y1941043D01*
X2158373Y1938709D01*
X2158809Y1936376D01*
X2159683Y1934626D01*
X2160993Y1933459D01*
X2162521Y1932876D01*
X2164049Y1933168D01*
X2165360Y1934042D01*
X2166233Y1935209D01*
G01X2179803Y1950376D02*
Y1932876D01*
G01X2176746Y1944542D02*
X2182860D01*
G01X2214803Y1950376D02*
Y1932876D01*
G01X2211746Y1944542D02*
X2217860D01*
G01X2228591Y1932876D02*
Y1950376D01*
G01Y1941918D02*
X2229683Y1943376D01*
X2230775Y1944251D01*
X2232521Y1944542D01*
X2233831Y1944251D01*
X2235360Y1943084D01*
X2236015Y1941334D01*
Y1932876D01*
G01X2249803Y1944542D02*
Y1932876D01*
G01Y1949209D02*
X2249366Y1949501D01*
Y1950084D01*
X2249803Y1950376D01*
X2250240Y1950084D01*
Y1949501D01*
X2249803Y1949209D01*
G01X2264028Y1934917D02*
X2265120Y1933751D01*
X2266648Y1932876D01*
X2267958D01*
X2269268Y1933459D01*
X2270141Y1934334D01*
X2270578Y1935500D01*
X2270360Y1937251D01*
X2269486Y1938126D01*
X2265556Y1939876D01*
X2264683Y1941918D01*
X2265120Y1943376D01*
X2265993Y1944251D01*
X2267303Y1944542D01*
X2268613Y1944251D01*
X2269923Y1943376D01*
G01X2299683Y1950376D02*
X2304923D01*
G01X2302303D02*
Y1932876D01*
G01X2299683D02*
X2304923D01*
G01X2313253D02*
Y1944542D01*
G01Y1941334D02*
X2313908Y1942793D01*
X2315000Y1943959D01*
X2316528Y1944542D01*
X2318056Y1943959D01*
X2319148Y1942793D01*
X2319803Y1941334D01*
Y1932876D01*
G01Y1941334D02*
X2320458Y1942793D01*
X2321549Y1943959D01*
X2323078Y1944542D01*
X2324606Y1943959D01*
X2325698Y1942793D01*
X2326353Y1941043D01*
Y1932876D01*
G01X2333373Y1927043D02*
Y1944542D01*
G01Y1941918D02*
X2334465Y1943376D01*
X2335556Y1944251D01*
X2337303Y1944542D01*
X2338831Y1944251D01*
X2340360Y1942793D01*
X2341015Y1940751D01*
X2341233Y1938709D01*
X2341015Y1936667D01*
X2340360Y1934626D01*
X2339049Y1933459D01*
X2337303Y1932876D01*
X2335775Y1933168D01*
X2334246Y1934042D01*
X2333373Y1935209D01*
G01X2351528Y1940751D02*
X2358515D01*
X2357860Y1942793D01*
X2356768Y1943959D01*
X2355240Y1944542D01*
X2353711Y1944251D01*
X2352401Y1943376D01*
X2351528Y1941334D01*
X2351091Y1939584D01*
Y1937834D01*
X2351528Y1936084D01*
X2352620Y1934334D01*
X2353930Y1933168D01*
X2355458Y1932876D01*
X2356986Y1933459D01*
X2358515Y1935209D01*
G01X2376233Y1950376D02*
Y1932876D01*
G01Y1935500D02*
X2375360Y1934042D01*
X2374049Y1933168D01*
X2372521Y1932876D01*
X2370775Y1933459D01*
X2369465Y1934917D01*
X2368591Y1936667D01*
X2368373Y1938709D01*
X2368591Y1940751D01*
X2369465Y1942501D01*
X2370775Y1943959D01*
X2372521Y1944542D01*
X2374049Y1944251D01*
X2375141Y1943667D01*
X2376233Y1942501D01*
G01X2393733Y1932876D02*
Y1944542D01*
G01Y1942501D02*
X2392860Y1943667D01*
X2391549Y1944251D01*
X2390021Y1944542D01*
X2388493Y1943959D01*
X2387183Y1942793D01*
X2386309Y1941043D01*
X2385873Y1938709D01*
X2386309Y1936376D01*
X2387183Y1934626D01*
X2388493Y1933459D01*
X2390021Y1932876D01*
X2391549Y1933168D01*
X2392860Y1934042D01*
X2393733Y1935209D01*
G01X2403591Y1932876D02*
Y1944542D01*
G01Y1941626D02*
X2404465Y1943084D01*
X2405775Y1944251D01*
X2407521Y1944542D01*
X2409049Y1944251D01*
X2410360Y1943084D01*
X2411015Y1941043D01*
Y1932876D01*
G01X2428296Y1943084D02*
X2426768Y1944251D01*
X2425458Y1944542D01*
X2423711Y1943959D01*
X2422401Y1942793D01*
X2421528Y1940751D01*
X2421309Y1938709D01*
X2421528Y1936667D01*
X2422401Y1934917D01*
X2423711Y1933459D01*
X2425458Y1932876D01*
X2426986Y1933459D01*
X2428296Y1934626D01*
G01X2439028Y1940751D02*
X2446015D01*
X2445360Y1942793D01*
X2444268Y1943959D01*
X2442740Y1944542D01*
X2441211Y1944251D01*
X2439901Y1943376D01*
X2439028Y1941334D01*
X2438591Y1939584D01*
Y1937834D01*
X2439028Y1936084D01*
X2440120Y1934334D01*
X2441430Y1933168D01*
X2442958Y1932876D01*
X2444486Y1933459D01*
X2446015Y1935209D01*
G01X1987303Y1909892D02*
Y1898226D01*
G01Y1914559D02*
X1986866Y1914851D01*
Y1915434D01*
X1987303Y1915726D01*
X1987740Y1915434D01*
Y1914851D01*
X1987303Y1914559D01*
G01X2001528Y1900267D02*
X2002620Y1899101D01*
X2004148Y1898226D01*
X2005458D01*
X2006768Y1898809D01*
X2007641Y1899684D01*
X2008078Y1900850D01*
X2007860Y1902601D01*
X2006986Y1903476D01*
X2003056Y1905226D01*
X2002183Y1907268D01*
X2002620Y1908726D01*
X2003493Y1909601D01*
X2004803Y1909892D01*
X2006113Y1909601D01*
X2007423Y1908726D01*
G01X2034781Y1898226D02*
Y1915726D01*
X2044825Y1898226D01*
Y1915726D01*
G01X2057303Y1898226D02*
X2055556Y1898518D01*
X2054028Y1899684D01*
X2052718Y1901434D01*
X2051844Y1903476D01*
X2051408Y1905809D01*
Y1908143D01*
X2051844Y1910476D01*
X2052718Y1912518D01*
X2054028Y1914267D01*
X2055556Y1915434D01*
X2057303Y1915726D01*
X2059049Y1915434D01*
X2060578Y1914267D01*
X2061888Y1912518D01*
X2062762Y1910476D01*
X2063198Y1908143D01*
Y1905809D01*
X2062762Y1903476D01*
X2061888Y1901434D01*
X2060578Y1899684D01*
X2059049Y1898518D01*
X2057303Y1898226D01*
G01X2074803Y1915726D02*
Y1898226D01*
G01X2069781Y1915726D02*
X2079825D01*
G01X2106091Y1909892D02*
Y1901726D01*
X2106965Y1899684D01*
X2108275Y1898518D01*
X2109803Y1898226D01*
X2111331Y1898518D01*
X2112641Y1899684D01*
X2113515Y1901726D01*
G01Y1898226D02*
Y1909892D01*
G01X2124028Y1900267D02*
X2125120Y1899101D01*
X2126648Y1898226D01*
X2127958D01*
X2129268Y1898809D01*
X2130141Y1899684D01*
X2130578Y1900850D01*
X2130360Y1902601D01*
X2129486Y1903476D01*
X2125556Y1905226D01*
X2124683Y1907268D01*
X2125120Y1908726D01*
X2125993Y1909601D01*
X2127303Y1909892D01*
X2128613Y1909601D01*
X2129923Y1908726D01*
G01X2141528Y1906101D02*
X2148515D01*
X2147860Y1908143D01*
X2146768Y1909309D01*
X2145240Y1909892D01*
X2143711Y1909601D01*
X2142401Y1908726D01*
X2141528Y1906684D01*
X2141091Y1904934D01*
Y1903184D01*
X2141528Y1901434D01*
X2142620Y1899684D01*
X2143930Y1898518D01*
X2145458Y1898226D01*
X2146986Y1898809D01*
X2148515Y1900559D01*
G01X2166233Y1915726D02*
Y1898226D01*
G01Y1900850D02*
X2165360Y1899392D01*
X2164049Y1898518D01*
X2162521Y1898226D01*
X2160775Y1898809D01*
X2159465Y1900267D01*
X2158591Y1902017D01*
X2158373Y1904059D01*
X2158591Y1906101D01*
X2159465Y1907851D01*
X2160775Y1909309D01*
X2162521Y1909892D01*
X2164049Y1909601D01*
X2165141Y1909017D01*
X2166233Y1907851D01*
G01X-7874Y0D02*
X-75552D01*
G02X-90552Y15000I0J15000D01*
G01Y519024D01*
G02X-75552Y534024I15000J0D01*
G01X-7874D01*
G01Y1030087D02*
X-75552D01*
G03X-90552Y1015087I0J-15000D01*
G01Y1001780D01*
G03X-75552Y986780I15000J0D01*
G01X-7874D01*
G01Y1992126D02*
X-75552D01*
G03X-90552Y1977126I0J-15000D01*
G01Y1915165D01*
G03X-75552Y1900165I15000J0D01*
G01X-7874D01*
G01X1023228Y1618051D02*
Y1675945D01*
G02X1028701Y1681417I5472J0D01*
G01X1033465D01*
X1037402Y1685354D01*
Y1988189D01*
G03X1033465Y1992126I-3937J0D01*
G01X3937D01*
G03X0Y1988189I0J-3937D01*
G01Y1661189D01*
X1969Y1659220D01*
X17323D01*
G02Y1650559I0J-4331D01*
G01X1969D01*
X0Y1648591D01*
Y1243866D01*
X1969Y1241898D01*
X17323D01*
G02Y1233236I0J-4331D01*
G01X1969D01*
X0Y1231268D01*
Y747803D01*
X1969Y745835D01*
X17323D01*
G02Y737173I0J-4331D01*
G01X1969D01*
X0Y735205D01*
Y3937D01*
G03X3937Y0I3937J0D01*
G01X121260D01*
X127310Y11888D01*
G03X127953Y14567I-5263J2680D01*
G01Y17717D01*
G02X139764I5906J0D01*
G01Y14567D01*
G03X140406Y11888I5906J-1D01*
G01X146457Y0D01*
X1033465D01*
G03X1037402Y3937I0J3937D01*
G01Y1424882D01*
X1033465Y1428819D01*
X1028701D01*
G02X1023228Y1434291I0J5473D01*
G01Y1609902D01*
X1021260Y1611870D01*
X993681D01*
G02Y1616083I0J2107D01*
G01X1021260D01*
X1023228Y1618051D01*
G01X-7874Y39059D02*
G03X0I3937J0D01*
G01Y8350D02*
G03X-7874I-3937J0D01*
G01D02*
Y0D01*
G01Y251657D02*
Y39059D01*
G01X0Y251657D02*
G03X-7874I-3937J0D01*
G01Y282366D02*
G03X0I3937J0D01*
G01X-7874Y494965D02*
Y282366D01*
G01Y525673D02*
G03X0I3937J0D01*
G01Y494965D02*
G03X-7874I-3937J0D01*
G01Y534024D02*
Y525673D01*
G01X0Y993079D02*
G03X-7874I-3937J0D01*
G01Y986780D02*
Y993079D01*
G01Y1023787D02*
G03X0I3937J0D01*
G01X-7874D02*
Y1030087D01*
G01Y1930791D02*
Y1900165D01*
G01X0Y1930791D02*
G03X-7874I-3937J0D01*
G01Y1961500D02*
G03X0I3937J0D01*
G01X-7874Y1992126D02*
Y1961500D01*
G01X1045276Y0D02*
X1112953D01*
G03X1127953Y15000I0J15000D01*
G01Y493259D01*
G01X1045276Y25827D02*
G03X1037402I-3937J0D01*
G01X1045276Y0D02*
Y25827D01*
G01X1037402Y56535D02*
G03X1045276I3937J0D01*
G01D02*
Y284882D01*
G01X1037402Y315591D02*
G03X1045276I3937J0D01*
G01Y284882D02*
G03X1037402I-3937J0D01*
G01X1045276Y315591D02*
Y543937D01*
G01D02*
G03X1037402I-3937J0D01*
G01Y574646D02*
G03X1045276I3937J0D01*
G01D02*
Y802992D01*
G01X1037402Y833701D02*
G03X1045276I3937J0D01*
G01Y802992D02*
G03X1037402I-3937J0D01*
G01X1045276Y833701D02*
Y1062047D01*
G01D02*
G03X1037402I-3937J0D01*
G01Y1092756D02*
G03X1045276I3937J0D01*
G01D02*
Y1321102D01*
G01D02*
G03X1037402I-3937J0D01*
G01Y1351811D02*
G03X1045276I3937J0D01*
G01D02*
Y1377638D01*
G01D02*
X1112953D01*
G02X1127953Y1362638I0J-15000D01*
G01Y501133D01*
G01X1045276Y1732598D02*
X1112953D01*
G03X1127953Y1747598I0J15000D01*
G01Y1977126D01*
G03X1112953Y1992126I-15000J0D01*
G01X1045276D01*
G01X1037402Y1767835D02*
G03X1045276I3937J0D01*
G01Y1737126D02*
G03X1037402I-3937J0D01*
G01X1045276Y1767835D02*
Y1956890D01*
G01Y1732598D02*
Y1737126D01*
G01X1037402Y1987598D02*
G03X1045276I3937J0D01*
G01Y1956890D02*
G03X1037402I-3937J0D01*
G01X1045276Y1987598D02*
Y1992126D01*
G01X1127953Y501133D02*
G03Y493259I0J-3937D01*
G54D12*
G01X61134Y368442D02*
X38506Y391070D01*
G01D02*
Y647257D01*
G01X36331Y645669D02*
Y390169D01*
G01D02*
X58308Y368192D01*
G01X52066Y370649D02*
X34156Y388559D01*
G01D02*
Y644344D01*
G01X31981Y643019D02*
Y387202D01*
G01D02*
X56024Y363159D01*
G01X38506Y647257D02*
X30088Y655675D01*
G01D02*
X22000D01*
G01D02*
X21325Y655000D01*
G01D02*
X15401D01*
G01D02*
X14662Y655739D01*
G01D02*
Y656838D01*
G01D02*
X13460Y658040D01*
G01D02*
X8858D01*
G01X37325Y730146D02*
Y652375D01*
G01D02*
X39086Y650614D01*
G01X8858Y654890D02*
X12798D01*
G01D02*
X14000Y653688D01*
G01D02*
X28312D01*
G01D02*
X36331Y645669D01*
G01X34156Y644344D02*
X25987Y652513D01*
G01D02*
X14791D01*
G01D02*
X14019Y651741D01*
G01D02*
X8858D01*
G01Y648591D02*
X13253D01*
G01D02*
X14662Y650000D01*
G01D02*
Y650722D01*
G01D02*
X15278Y651338D01*
G01D02*
X23662D01*
G01D02*
X31981Y643019D01*
G01X27699Y737535D02*
X29936D01*
G01D02*
X37325Y730146D01*
G01X8858Y752528D02*
X12972D01*
G01D02*
X15680Y749820D01*
G01D02*
X27680D01*
G01D02*
X41901Y735599D01*
G01X28426Y783500D02*
X48926Y763000D01*
G01X27675Y781175D02*
X46751Y762099D01*
G01X44576Y761198D02*
X25774Y780000D01*
G01X8858Y749378D02*
X14222D01*
G01D02*
X14955Y748645D01*
G01D02*
X22655D01*
G01D02*
X39500Y731800D01*
G01X43555Y776945D02*
X34872Y785628D01*
G01D02*
Y890906D01*
G01X8858Y787174D02*
X12826D01*
G01D02*
X14596Y785404D01*
G01D02*
Y784999D01*
G01D02*
X16095Y783500D01*
G01D02*
X28426D01*
G01X8858Y784024D02*
X12976D01*
G01D02*
X15825Y781175D01*
G01D02*
X27675D01*
G01X25774Y780000D02*
X14000D01*
G01D02*
X13126Y780874D01*
G01D02*
X8858D01*
G01Y916308D02*
X12794D01*
G01D02*
X14596Y918110D01*
G01D02*
Y918434D01*
G01D02*
X16162Y920000D01*
G01D02*
X21000D01*
G01D02*
X30000Y929000D01*
G01X8858Y919457D02*
X13957D01*
G01D02*
X16675Y922175D01*
G01X30000Y929000D02*
Y991000D01*
G01X8858Y922607D02*
X14500D01*
G01D02*
X15393Y923500D01*
G01D02*
X17748D01*
G01D02*
X25650Y931402D01*
G01D02*
Y987350D01*
G01D02*
X25000Y988000D01*
G01X16675Y922175D02*
X20099D01*
G01D02*
X27825Y929901D01*
G01D02*
Y995000D01*
G01X23291Y1062791D02*
X31707D01*
G01X37657Y1125065D02*
X41608D01*
G01X8858Y1119457D02*
X12793D01*
G01D02*
X14596Y1121260D01*
G01D02*
Y1122096D01*
G01D02*
X15579Y1123079D01*
G01D02*
X29481D01*
G01D02*
X31467Y1125065D01*
G01D02*
X37657D01*
G01X39286Y1122002D02*
X32335D01*
G01X33971Y1131741D02*
X28915D01*
G01D02*
X26829Y1129655D01*
G01D02*
X16579D01*
G01D02*
X15830Y1128906D01*
G01D02*
X8858D01*
G01X39959Y1128308D02*
X36827D01*
G01D02*
X35910Y1127391D01*
G01D02*
X30717D01*
G01D02*
X28580Y1125254D01*
G01D02*
X15754D01*
G01D02*
X13107Y1122607D01*
G01D02*
X8858D01*
G01X37396Y1130912D02*
X36355D01*
G01D02*
X35009Y1129566D01*
G01D02*
X29816D01*
G01D02*
X27679Y1127429D01*
G01D02*
X15929D01*
G01D02*
X14256Y1125756D01*
G01D02*
X8858D01*
G01X40097Y1157930D02*
X37070Y1160957D01*
G01D02*
Y1226805D01*
G01X8858Y1245441D02*
X13429D01*
G01D02*
X14162Y1244708D01*
G01D02*
X25792D01*
G01D02*
X30900Y1239600D01*
G01D02*
Y1236537D01*
G01D02*
X32959Y1234478D01*
G01X8858Y1248591D02*
X12909D01*
G01D02*
X15617Y1245883D01*
G01D02*
X29117D01*
G01D02*
X36000Y1239000D01*
G01D02*
Y1236000D01*
G01X39245Y1277255D02*
X33699Y1282801D01*
G01D02*
Y1301782D01*
G01X36853Y1285816D02*
X41420Y1281249D01*
G01X37070Y1226805D02*
X33201Y1230674D01*
G01X8858Y1302134D02*
X12793D01*
G01D02*
X14596Y1303937D01*
G01D02*
Y1304200D01*
G01D02*
X16396Y1306000D01*
G01D02*
X21500D01*
G01D02*
X24500Y1303000D01*
G01D02*
X31000D01*
G01D02*
X33938Y1305938D01*
G01D02*
Y1311000D01*
G01X8858Y1305284D02*
X13025D01*
G01D02*
X15000Y1307259D01*
G01D02*
X27741D01*
G01D02*
X30000Y1305000D01*
G01X38500Y1311000D02*
X39028Y1310472D01*
G01X36170Y1308434D02*
X36853Y1307751D01*
G01D02*
Y1285816D01*
G01X8858Y1308434D02*
X24934D01*
G01D02*
X25500Y1309000D01*
G01D02*
X30300D01*
G01D02*
X30700Y1308600D01*
G01X28000Y1444000D02*
Y1426605D01*
G01D02*
X20070Y1418675D01*
G01D02*
X15511D01*
G01D02*
X15506Y1418670D01*
G01D02*
X8858D01*
G01Y1415520D02*
X14018D01*
G01D02*
X15998Y1417500D01*
G01D02*
X27000D01*
G01X8858Y1412371D02*
X13371D01*
G01D02*
X14662Y1413662D01*
G01D02*
Y1414502D01*
G01D02*
X15739Y1415579D01*
G01D02*
X30579D01*
G01D02*
X32000Y1417000D01*
G01D02*
Y1417100D01*
G01D02*
X32500Y1417600D01*
G01X45193Y1565807D02*
X33276Y1577724D01*
G01X39800Y1557700D02*
X22500Y1575000D01*
G01D02*
X15901D01*
G01D02*
X14662Y1573761D01*
G01D02*
Y1573162D01*
G01D02*
X12925Y1571425D01*
G01D02*
X8858D01*
G01X43000Y1560500D02*
X26951Y1576549D01*
G01X15401D02*
X13426Y1574574D01*
G01D02*
X8858D01*
G01X33276Y1577724D02*
X8858D01*
G01Y1647015D02*
X14300D01*
G01D02*
X15033Y1647748D01*
G01D02*
X27924D01*
G01D02*
X31143Y1644529D01*
G01D02*
Y1644433D01*
G01D02*
X32337Y1643239D01*
G01D02*
Y1596270D01*
G01D02*
X38925Y1589682D01*
G01X26951Y1576549D02*
X15401D01*
G01X47254Y1587961D02*
X34512Y1600703D01*
G01D02*
Y1653244D01*
G01X37500Y1581000D02*
X30162Y1588338D01*
G01D02*
Y1642338D01*
G01D02*
X27000Y1645500D01*
G01D02*
X23073D01*
G01D02*
X22000Y1646573D01*
G01D02*
X15673D01*
G01D02*
X12966Y1643866D01*
G01D02*
X8858D01*
G01X47368Y1571132D02*
X37500Y1581000D01*
G01X35900Y1706000D02*
X14858D01*
G01D02*
X14000Y1706858D01*
G01D02*
X8858D01*
G01X34224Y1709000D02*
X25324D01*
G01D02*
X23499Y1707175D01*
G01D02*
X15825D01*
G01D02*
X12993Y1710007D01*
G01D02*
X8858D01*
G01X34512Y1653244D02*
X25725Y1662031D01*
G01D02*
X15169D01*
G01D02*
X14437Y1662763D01*
G01D02*
X8858D01*
G01Y1713157D02*
X12793D01*
G01D02*
X14596Y1711354D01*
G01D02*
Y1711305D01*
G01D02*
X16401Y1709500D01*
G01D02*
X22700D01*
G01D02*
X28200Y1715000D01*
G01D02*
X38000D01*
G01X8858Y1665913D02*
X12987D01*
G01D02*
X15694Y1663206D01*
G01D02*
X30532D01*
G01D02*
X41100Y1652638D01*
G01X33325Y1970275D02*
Y1968025D01*
G01D02*
X37300Y1964050D01*
G01D02*
X41800D01*
G01X33325Y1970275D02*
X30225D01*
G01D02*
X30200Y1970300D01*
G01X36825Y1970275D02*
X40825D01*
G01X110600Y49200D02*
X107538Y46138D01*
G01D02*
X107529D01*
G01D02*
X106891Y45500D01*
G01D02*
X99600D01*
G01D02*
X95871Y41771D01*
G01D02*
X89764D01*
G01X78839Y66161D02*
X68839D01*
G01D02*
X56500Y78500D01*
G01D02*
Y167000D01*
G01X112800Y49200D02*
X110600D01*
G01X78839Y96161D02*
X72500D01*
G01D02*
X58675Y109986D01*
G01D02*
Y165675D01*
G01X78839Y61161D02*
X72500D01*
G01X77205Y118937D02*
X71624D01*
G01D02*
X69946Y120615D01*
G01X56500Y167000D02*
X64771Y175271D01*
G01D02*
X70919D01*
G01D02*
X79945Y184297D01*
G01D02*
X102861D01*
G01D02*
X124625Y162533D01*
G01X126800Y163700D02*
X104028Y186472D01*
G01D02*
X79044D01*
G01D02*
X77072Y184500D01*
G01D02*
X59400D01*
G01D02*
X54846Y189054D01*
G01D02*
Y214958D01*
G01X58675Y165675D02*
X65875Y172875D01*
G01D02*
X110608D01*
G01D02*
X122450Y161033D01*
G01X69946Y120615D02*
X71417Y122086D01*
G01D02*
X77205D01*
G01X69946Y120615D02*
X65060D01*
G01D02*
X60850Y124825D01*
G01D02*
Y164774D01*
G01D02*
X66776Y170700D01*
G01D02*
X109707D01*
G01D02*
X118832Y161575D01*
G01X87589Y230965D02*
Y225909D01*
G01X80708Y224359D02*
X82129D01*
G01D02*
X84325Y222163D01*
G01D02*
X86589D01*
G01D02*
X87589Y223163D01*
G01D02*
Y225909D01*
G01X116100Y255500D02*
X111436Y260164D01*
G01D02*
X77970Y293630D01*
G01X91231Y246983D02*
Y251734D01*
G01D02*
X89500Y253465D01*
G01D02*
X86000D01*
G01D02*
X80750D01*
G01X58308Y368192D02*
Y256808D01*
G01D02*
X56500Y255000D01*
G01D02*
Y216612D01*
G01X54846Y214958D02*
X56500Y216612D01*
G01X75710Y206668D02*
X82832D01*
G01D02*
X87500Y202000D01*
G01X92750Y205500D02*
Y201000D01*
G01D02*
X88500D01*
G01D02*
X87500Y202000D01*
G01X101750Y220090D02*
X97410D01*
G01D02*
X97400Y220100D01*
G01D02*
Y220200D01*
G01X78500Y239715D02*
Y245488D01*
G01D02*
X77600Y246388D01*
G01D02*
X74711D01*
G01X78500Y239715D02*
Y237988D01*
G01D02*
X76750Y236238D01*
G01D02*
Y234322D01*
G01X74711Y246388D02*
X71400D01*
G01D02*
X70500Y245488D01*
G01D02*
Y242988D01*
G01X77250Y253465D02*
X72000D01*
G01D02*
X62500D01*
G01D02*
X59625Y250590D01*
G01D02*
Y237715D01*
G01X87589Y234465D02*
X83589D01*
G01X87589D02*
X93529D01*
G01D02*
X94469Y235405D01*
G01D02*
Y243674D01*
G01D02*
X95218Y244423D01*
G01D02*
X97731D01*
G01X83589Y234465D02*
X80300D01*
G01X69960Y209868D02*
X66680D01*
G01D02*
X63903Y212645D01*
G01D02*
Y216816D01*
G01D02*
X64734Y217647D01*
G01X73208Y220484D02*
X67784D01*
G01D02*
X64947Y217647D01*
G01D02*
X64734D01*
G01X94250Y223965D02*
X90233Y219948D01*
G01D02*
X81483D01*
G01D02*
X80708Y219173D01*
G01D02*
Y216609D01*
G01X92750Y214465D02*
X82852D01*
G01D02*
X80708Y216609D01*
G01X94250Y223965D02*
X97731Y227446D01*
G01D02*
Y234237D01*
G01D02*
Y241863D01*
G01X70819Y230822D02*
X76750D01*
G01X70819D02*
X68178D01*
G01D02*
X67375Y231625D01*
G01D02*
Y237715D01*
G01X106782Y268794D02*
X117576Y258000D01*
G01X59859Y204921D02*
X64140D01*
G01D02*
X65887Y206668D01*
G01D02*
X69960D01*
G01X59750Y223465D02*
Y228650D01*
G01D02*
X63500Y232400D01*
G01D02*
Y245215D01*
G01X59859Y204921D02*
X58091D01*
G01D02*
X57021Y205991D01*
G01D02*
Y213110D01*
G01D02*
X59750Y215839D01*
G01D02*
Y223465D01*
G01X87600Y209868D02*
X90268D01*
G01D02*
X90400Y210000D01*
G01D02*
X92750D01*
G01X75710Y209868D02*
X87600D01*
G01X77970Y293630D02*
X64863D01*
G01D02*
X61134Y297359D01*
G01D02*
Y368442D01*
G01X64847Y368307D02*
Y297719D01*
G01D02*
X66610Y295956D01*
G01X56024Y363159D02*
Y292549D01*
G01X67022Y369208D02*
Y308554D01*
G01D02*
X106782Y268794D01*
G01X40848Y648852D02*
Y392306D01*
G01D02*
X64847Y368307D01*
G01X113650Y373900D02*
X107750D01*
G01X94500Y372750D02*
X102750D01*
G01D02*
X104000Y371500D01*
G01D02*
Y367175D01*
G01D02*
X99575Y362750D01*
G01X78675Y380704D02*
X81604Y377775D01*
G01D02*
X85425D01*
G01D02*
Y375701D01*
G01D02*
X88376Y372750D01*
G01D02*
X90000D01*
G01D02*
X94500D01*
G01X84700Y348000D02*
Y342500D01*
G01D02*
X85950Y341250D01*
G01X107200Y342500D02*
X103000D01*
G01D02*
X101750Y341250D01*
G01D02*
X99700D01*
G01D02*
X95700D01*
G01D02*
X91200D01*
G01D02*
X85950D01*
G01X100250Y377775D02*
X93825D01*
G01X88925D02*
X93825D01*
G01X84700Y357000D02*
X86450Y355250D01*
G01D02*
X95700D01*
G01D02*
Y351550D01*
G01D02*
X95950Y351300D01*
G01D02*
Y349000D01*
G01X90700Y349600D02*
Y345250D01*
G01D02*
X91200Y344750D01*
G01X90700Y349600D02*
X93100D01*
G01D02*
X93700Y349000D01*
G01D02*
X95950D01*
G01X43023Y650616D02*
Y393207D01*
G01D02*
X67022Y369208D01*
G01X78839Y466673D02*
X72500D01*
G01X89764Y447283D02*
X93583D01*
G01D02*
X94700Y448400D01*
G01D02*
X102600D01*
G01D02*
X104900Y446100D01*
G01D02*
X114300D01*
G01X60325Y568825D02*
Y483848D01*
G01D02*
X72500Y471673D01*
G01D02*
X78839D01*
G01Y501673D02*
X72500D01*
G01D02*
X62500Y511673D01*
G01D02*
Y567924D01*
G01X77205Y527598D02*
X74134D01*
G01D02*
X71000Y524464D01*
G01X77205Y524449D02*
X71015D01*
G01D02*
X71000Y524464D01*
G01X82129Y629871D02*
X84325Y627675D01*
G01D02*
X86589D01*
G01D02*
X87589Y628675D01*
G01D02*
Y631421D01*
G01X62500Y567924D02*
X69901Y575325D01*
G01D02*
X111099D01*
G01D02*
X116782Y569642D01*
G01X94250Y629477D02*
X97731Y632958D01*
G01X92750Y619977D02*
X82852D01*
G01D02*
X80708Y622121D01*
G01X94250Y629477D02*
X90273Y625500D01*
G01D02*
X81523D01*
G01D02*
X80708Y624685D01*
G01D02*
Y622121D01*
G01X92750Y615500D02*
X89138D01*
G01D02*
X88000Y616638D01*
G01D02*
X82962D01*
G01X75710Y615380D02*
X78297D01*
G01D02*
X79555Y616638D01*
G01D02*
X82962D01*
G01X128590Y598338D02*
X101750Y625178D01*
G01D02*
Y625602D01*
G01X88600Y623300D02*
X94900D01*
G01D02*
X97202Y625602D01*
G01D02*
X101750D01*
G01X64734Y623159D02*
Y622775D01*
G01D02*
X69960Y617549D01*
G01D02*
Y615380D01*
G01X64734Y623159D02*
Y625532D01*
G01D02*
X67414Y628212D01*
G01D02*
X70992D01*
G01D02*
X73208Y625996D01*
G01X75710Y612180D02*
X82420D01*
G01D02*
X86500Y608100D01*
G01X92500Y606750D02*
X87850D01*
G01D02*
X86500Y608100D01*
G01X92500Y606750D02*
Y608750D01*
G01D02*
X92750Y609000D01*
G01D02*
Y611000D01*
G01X63623Y614620D02*
Y617569D01*
G01D02*
X61523Y619669D01*
G01D02*
Y630374D01*
G01X63623Y614620D02*
X64252D01*
G01D02*
X66692Y612180D01*
G01D02*
X69960D01*
G01X112000Y577501D02*
X70801D01*
G01D02*
X70800Y577500D01*
G01D02*
X69000D01*
G01D02*
X60325Y568825D01*
G01X77250Y658977D02*
X72000D01*
G01X59625Y643227D02*
X60600Y644202D01*
G01D02*
Y657077D01*
G01D02*
X62500Y658977D01*
G01D02*
X72000D01*
G01X39086Y650614D02*
X40848Y648852D01*
G01X80708Y629871D02*
X82129D01*
G01X87589Y636477D02*
Y631421D01*
G01X48000Y649500D02*
X47240D01*
G01D02*
X41901Y654839D01*
G01D02*
Y716960D01*
G01X97731Y639749D02*
Y647375D01*
G01Y632958D02*
Y639749D01*
G01X70621Y636334D02*
X68250D01*
G01D02*
X67375Y637209D01*
G01D02*
Y643227D01*
G01X70621Y636334D02*
X76750D01*
G01X50560Y726940D02*
Y653500D01*
G01X47500Y726924D02*
Y660500D01*
G01X83589Y639977D02*
X80300D01*
G01X83589D02*
X87589D01*
G01D02*
X93492D01*
G01D02*
X94492Y640977D01*
G01D02*
Y648969D01*
G01D02*
X95458Y649935D01*
G01D02*
X97731D01*
G01X76750Y639834D02*
Y641750D01*
G01D02*
X78500Y643500D01*
G01D02*
Y645227D01*
G01D02*
Y651000D01*
G01D02*
X77600Y651900D01*
G01D02*
X74711D01*
G01D02*
X71400D01*
G01D02*
X70500Y651000D01*
G01D02*
Y648500D01*
G01X46500Y653500D02*
X44576Y655424D01*
G01D02*
Y724360D01*
G01X39500Y731800D02*
Y654139D01*
G01D02*
X43023Y650616D01*
G01X91231Y652495D02*
Y657246D01*
G01D02*
X89500Y658977D01*
G01D02*
X86000D01*
G01D02*
X80750D01*
G01X63500Y650727D02*
Y639000D01*
G01D02*
X61523Y637023D01*
G01D02*
Y630374D01*
G01X49500Y771000D02*
X43555Y776945D01*
G01X41901Y735599D02*
Y716960D01*
G01X95950Y754500D02*
Y760500D01*
G01D02*
X95700Y760750D01*
G01X84700Y762500D02*
X93950D01*
G01D02*
X95700Y760750D01*
G01X90700Y755100D02*
Y750750D01*
G01D02*
X91200Y750250D01*
G01X90700Y755100D02*
X93100D01*
G01D02*
X93700Y754500D01*
G01D02*
X95950D01*
G01X48926Y763000D02*
Y728574D01*
G01D02*
X50560Y726940D01*
G01X107200Y748000D02*
X103100D01*
G01D02*
X101850Y746750D01*
G01D02*
X99700D01*
G01D02*
X95700D01*
G01D02*
X91200D01*
G01D02*
X85950D01*
G01X84700Y753500D02*
Y748000D01*
G01D02*
X85950Y746750D01*
G01X99575Y768250D02*
X101375D01*
G01D02*
X104000Y770875D01*
G01D02*
Y777000D01*
G01X46751Y762099D02*
Y727673D01*
G01D02*
X47500Y726924D01*
G01X44576Y724360D02*
Y761198D01*
G01X113650Y779400D02*
X107750D01*
G01X88925Y783275D02*
X93825D01*
G01X100250D02*
X93825D01*
G01X161600Y792100D02*
X67745D01*
G01D02*
X47500Y812345D01*
G01D02*
Y901500D01*
G01X104000Y777000D02*
X102750Y778250D01*
G01D02*
X94500D01*
G01X80215Y777137D02*
Y781715D01*
G01D02*
X81775Y783275D01*
G01D02*
X85425D01*
G01D02*
X90000Y778700D01*
G01D02*
Y778250D01*
G01D02*
X94500D01*
G01X114900Y851500D02*
X104100D01*
G01D02*
X101400Y854200D01*
G01D02*
X95100D01*
G01D02*
X93695Y852795D01*
G01D02*
X89764D01*
G01X78839Y907185D02*
X68815D01*
G01D02*
X63157Y912843D01*
G01D02*
Y1001872D01*
G01X78839Y877185D02*
X68315D01*
G01D02*
X60982Y884518D01*
G01D02*
Y1002773D01*
G01X78839Y872185D02*
X72500D01*
G01X77205Y933110D02*
X71854D01*
G01D02*
X71376Y932632D01*
G01D02*
Y930946D01*
G01D02*
X72361Y929961D01*
G01X77205D02*
X72361D01*
G01D02*
X71000Y928600D01*
G01D02*
Y925500D01*
G01X83019Y1007605D02*
X164299Y926325D01*
G01X85194Y1008506D02*
X165200Y928500D01*
G01X45000Y1060750D02*
Y1057000D01*
G01X77250Y1064488D02*
X72000D01*
G01D02*
X66488D01*
G01D02*
X63782Y1061782D01*
G01D02*
Y1051407D01*
G01D02*
X63125Y1050750D01*
G01X92750Y1021000D02*
X88149D01*
G01D02*
X87000Y1022149D01*
G01D02*
X82962D01*
G01X75710Y1020891D02*
X78297D01*
G01D02*
X79555Y1022149D01*
G01D02*
X82962D01*
G01X66945Y1012436D02*
Y1011812D01*
G01D02*
X64730Y1009597D01*
G01D02*
X62270D01*
G01D02*
X60982Y1010885D01*
G01D02*
Y1033982D01*
G01D02*
X64500Y1037500D01*
G01X69960Y1017691D02*
Y1015451D01*
G01D02*
X66945Y1012436D01*
G01X67000Y1058250D02*
Y1049500D01*
G01D02*
X64500Y1047000D01*
G01D02*
Y1037500D01*
G01X64040Y1023735D02*
X64068Y1023707D01*
G01D02*
X68448D01*
G01D02*
X69960Y1022195D01*
G01D02*
Y1020891D01*
G01X64040Y1023735D02*
Y1027976D01*
G01D02*
X64734Y1028670D01*
G01X73208Y1031507D02*
X67571D01*
G01D02*
X64734Y1028670D01*
G01X97731Y1045260D02*
Y1052886D01*
G01X94250Y1034988D02*
X97731Y1038469D01*
G01D02*
Y1045260D01*
G01X92750Y1025488D02*
X82852D01*
G01D02*
X80708Y1027632D01*
G01X94250Y1034988D02*
X90262Y1031000D01*
G01D02*
X81512D01*
G01D02*
X80708Y1030196D01*
G01D02*
Y1027632D01*
G01X70875Y1050750D02*
Y1044000D01*
G01X77750Y1040845D02*
X71455D01*
G01D02*
X70875Y1041425D01*
G01D02*
Y1044000D01*
G01X63157Y1001872D02*
X68890Y1007605D01*
G01D02*
X83019D01*
G01X45000Y1076500D02*
Y1064250D01*
G01X41000Y1070000D02*
Y1064250D01*
G01X134000Y1014500D02*
X108700Y1039800D01*
G01D02*
Y1055529D01*
G01D02*
X97812Y1066417D01*
G01X41000Y1060750D02*
Y1057500D01*
G01X75710Y1017691D02*
X82509D01*
G01D02*
X86000Y1014200D01*
G01X93000Y1012250D02*
X87950D01*
G01D02*
X86000Y1014200D01*
G01X92750Y1016500D02*
Y1014350D01*
G01D02*
X93000Y1014100D01*
G01D02*
Y1012250D01*
G01X88000Y1037507D02*
Y1042750D01*
G01Y1037507D02*
Y1034500D01*
G01D02*
X87000Y1033500D01*
G01D02*
X82590D01*
G01D02*
X80708Y1035382D01*
G01X81689Y1049400D02*
Y1048561D01*
G01D02*
X84000Y1046250D01*
G01X88000D02*
X92750D01*
G01D02*
X94492Y1047992D01*
G01D02*
Y1054792D01*
G01D02*
X95146Y1055446D01*
G01D02*
X97731D01*
G01X84000Y1046250D02*
X88000D01*
G01X101750Y1031113D02*
X104987D01*
G01D02*
X106100Y1030000D01*
G01X60982Y1002773D02*
X67989Y1009780D01*
G01D02*
X83921D01*
G01D02*
X85194Y1008507D01*
G01D02*
Y1008506D01*
G01X86000Y1064488D02*
X89612D01*
G01D02*
X91231Y1062869D01*
G01D02*
Y1058006D01*
G01X86000Y1064488D02*
X80750D01*
G01X77750Y1049386D02*
X75886D01*
G01D02*
X74000Y1047500D01*
G01X77750Y1044345D02*
Y1049386D01*
G01X42286Y1085500D02*
X39319Y1088467D01*
G01D02*
Y1106897D01*
G01D02*
X41840Y1109418D01*
G01D02*
Y1115552D01*
G01D02*
Y1119448D01*
G01D02*
X39286Y1122002D01*
G01X42286Y1104286D02*
Y1106512D01*
G01D02*
X44178Y1108404D01*
G01D02*
Y1157152D01*
G01X42286Y1089500D02*
Y1104286D01*
G01X48528Y1178895D02*
Y1080028D01*
G01D02*
X45000Y1076500D01*
G01X46353Y1176910D02*
Y1081353D01*
G01D02*
X41000Y1076000D01*
G01D02*
Y1070000D01*
G01X97812Y1066417D02*
X93869Y1070360D01*
G01D02*
X67090D01*
G01X84700Y1168400D02*
X93950D01*
G01D02*
X95700Y1166650D01*
G01D02*
Y1162950D01*
G01D02*
X95950Y1162700D01*
G01D02*
Y1160400D01*
G01X90700Y1161000D02*
X93100D01*
G01D02*
X93700Y1160400D01*
G01D02*
X95950D01*
G01X90700Y1161000D02*
Y1156650D01*
G01D02*
X91200Y1156150D01*
G01X94500Y1183750D02*
X102750D01*
G01D02*
X104000Y1182500D01*
G01D02*
Y1178575D01*
G01D02*
X99575Y1174150D01*
G01X85425Y1188775D02*
Y1185925D01*
G01D02*
X85300Y1185800D01*
G01D02*
Y1182000D01*
G01D02*
X88250D01*
G01D02*
X90000Y1183750D01*
G01D02*
X94500D01*
G01X44178Y1157152D02*
X39245Y1162085D01*
G01D02*
Y1277255D01*
G01X43595Y1282150D02*
Y1183828D01*
G01D02*
X48528Y1178895D01*
G01X41420Y1281249D02*
Y1181843D01*
G01D02*
X46353Y1176910D01*
G01X100250Y1188775D02*
X93825D01*
G01X88925D02*
X93825D01*
G01X40097Y1142513D02*
Y1154992D01*
G01D02*
Y1157930D01*
G01X113650Y1184900D02*
X107750D01*
G01X84700Y1159400D02*
Y1153900D01*
G01D02*
X85950Y1152650D01*
G01X107200Y1153900D02*
X102900D01*
G01D02*
X101650Y1152650D01*
G01D02*
X99700D01*
G01D02*
X95700D01*
G01D02*
X91200D01*
G01D02*
X85950D01*
G01X78839Y1277697D02*
X72500D01*
G01X78839Y1282697D02*
X72500D01*
G01D02*
X69500Y1285697D01*
G01X89764Y1258307D02*
X93907D01*
G01D02*
X95100Y1259500D01*
G01D02*
X101700D01*
G01D02*
X104300Y1256900D01*
G01D02*
X114900D01*
G01X39028Y1286717D02*
X43595Y1282150D01*
G01X58900Y1317000D02*
X60800Y1318900D01*
G01D02*
Y1323900D01*
G01D02*
X59825Y1324875D01*
G01D02*
Y1396082D01*
G01X69500Y1285697D02*
Y1312500D01*
G01D02*
X64400Y1317600D01*
G01D02*
Y1324400D01*
G01D02*
X62000Y1326800D01*
G01D02*
Y1385076D01*
G01X78839Y1312697D02*
X73303D01*
G01D02*
X67100Y1318900D01*
G01D02*
Y1333200D01*
G01D02*
X64500Y1335800D01*
G01D02*
Y1384500D01*
G01X77205Y1335473D02*
X71015D01*
G01D02*
X71000Y1335488D01*
G01X77205Y1338622D02*
X74134D01*
G01D02*
X71000Y1335488D01*
G01X39028Y1310472D02*
Y1286717D01*
G01X63200Y1432648D02*
Y1429835D01*
G01D02*
X63797Y1429238D01*
G01D02*
X66263D01*
G01D02*
X69098Y1426403D01*
G01D02*
X69960D01*
G01X59825Y1396082D02*
X63964Y1400221D01*
G01D02*
X79061D01*
G01D02*
X91104Y1412264D01*
G01D02*
X98364D01*
G01D02*
X102600Y1416500D01*
G01D02*
Y1435775D01*
G01X62000Y1385076D02*
X65600Y1388676D01*
G01D02*
X67400D01*
G01D02*
X67401Y1388675D01*
G01D02*
X109401D01*
G01D02*
X120158Y1377918D01*
G01X64500Y1384500D02*
X66500Y1386500D01*
G01D02*
X108500D01*
G01D02*
X117983Y1377017D01*
G01X92750Y1426500D02*
X89161D01*
G01D02*
X88000Y1427661D01*
G01D02*
X82962D01*
G01D02*
X79555D01*
G01D02*
X78297Y1426403D01*
G01D02*
X75710D01*
G01X67590Y1417910D02*
X69047D01*
G01D02*
X69960Y1418823D01*
G01D02*
Y1423203D01*
G01X67590Y1417910D02*
Y1417154D01*
G01D02*
X65507Y1415071D01*
G01D02*
X62915D01*
G01D02*
X59877Y1418109D01*
G01D02*
Y1432401D01*
G01X92750Y1422000D02*
Y1417500D01*
G01X75710Y1423203D02*
X84797D01*
G01D02*
X87500Y1420500D01*
G01X92750Y1417500D02*
X90500D01*
G01D02*
X87500Y1420500D01*
G01X76750Y1455100D02*
Y1450857D01*
G01X73000Y1455100D02*
X76750D01*
G01X64734Y1434182D02*
X63200Y1432648D01*
G01X73208Y1437019D02*
X66919D01*
G01D02*
X64734Y1434834D01*
G01D02*
Y1434182D01*
G01X104000Y1482000D02*
Y1485500D01*
G01D02*
X109346Y1490846D01*
G01D02*
X113957D01*
G01X102600Y1435775D02*
X101750Y1436625D01*
G01X97731Y1450772D02*
Y1458398D01*
G01X94250Y1440500D02*
X97731Y1443981D01*
G01D02*
Y1450772D01*
G01X92750Y1431000D02*
X82852D01*
G01D02*
X80708Y1433144D01*
G01X94250Y1440500D02*
X90750Y1437000D01*
G01D02*
X82000D01*
G01D02*
X80708Y1435708D01*
G01D02*
Y1433144D01*
G01X69365Y1474719D02*
X71141Y1476495D01*
G01D02*
X82137D01*
G01D02*
X98795D01*
G01D02*
X111837Y1463453D01*
G01X114000Y1476750D02*
X110000D01*
G01X67375Y1454250D02*
Y1448425D01*
G01D02*
X68443Y1447357D01*
G01D02*
X70273D01*
G01D02*
X76750D01*
G01X59625Y1454250D02*
X60200Y1454825D01*
G01D02*
Y1467700D01*
G01D02*
X62500Y1470000D01*
G01D02*
X72000D01*
G01X77250D02*
X72000D01*
G01X59877Y1432401D02*
X62000Y1434524D01*
G01D02*
Y1441800D01*
G01D02*
Y1447500D01*
G01D02*
X63500Y1449000D01*
G01D02*
Y1461750D01*
G01X86000Y1470000D02*
X89200D01*
G01D02*
X91231Y1467969D01*
G01D02*
Y1463518D01*
G01X86000Y1470000D02*
X80750D01*
G01X83589Y1451000D02*
X80300D01*
G01X83589D02*
X87589D01*
G01D02*
X93492D01*
G01D02*
X94492Y1452000D01*
G01D02*
Y1459992D01*
G01D02*
X95458Y1460958D01*
G01D02*
X97731D01*
G01X87589Y1447500D02*
Y1442444D01*
G01D02*
Y1440344D01*
G01D02*
X86745Y1439500D01*
G01D02*
X84000D01*
G01D02*
X82606Y1440894D01*
G01D02*
X80708D01*
G01X75256Y1583625D02*
Y1567742D01*
G01D02*
X77607Y1565391D01*
G01X98875Y1577768D02*
Y1570250D01*
G01X42644Y1521957D02*
X45193Y1524506D01*
G01D02*
Y1565807D01*
G01X42960Y1517408D02*
X39800Y1520568D01*
G01D02*
Y1547400D01*
G01D02*
Y1557700D01*
G01X43000Y1554900D02*
Y1560500D01*
G01Y1554900D02*
X42855D01*
G01X43000D02*
Y1526000D01*
G01X46893Y1519979D02*
X49543Y1522629D01*
G01D02*
Y1585672D01*
G01X99000Y1548750D02*
X95000D01*
G01D02*
X90500D01*
G01D02*
X85250D01*
G01X84000Y1555500D02*
Y1550000D01*
G01D02*
X85250Y1548750D01*
G01X99000D02*
X100650D01*
G01D02*
X102900Y1551000D01*
G01D02*
Y1552300D01*
G01D02*
X104700Y1554100D01*
G01D02*
X106700D01*
G01X47368Y1527323D02*
Y1571132D01*
G01X46845Y1514264D02*
X51718Y1519137D01*
G01D02*
Y1595562D01*
G01X90500Y1552250D02*
X90000Y1552750D01*
G01D02*
Y1556800D01*
G01D02*
X90300Y1557100D01*
G01X84000Y1564500D02*
X86800D01*
G01D02*
X88550Y1562750D01*
G01D02*
X95000D01*
G01D02*
X95250Y1562500D01*
G01D02*
Y1556500D01*
G01D02*
X93000D01*
G01D02*
X92400Y1557100D01*
G01D02*
X90300D01*
G01X75256Y1583625D02*
X79375D01*
G01X83875D02*
X79375D01*
G01X83875D02*
X85999D01*
G01D02*
X86580Y1584206D01*
G01D02*
X92437D01*
G01D02*
X98875Y1577768D01*
G01X38925Y1589682D02*
X42919Y1585688D01*
G01D02*
Y1583175D01*
G01X49543Y1585672D02*
X47254Y1587961D01*
G01X41100Y1652638D02*
Y1633650D01*
G01X154350Y1610000D02*
X83509D01*
G01D02*
X64525Y1591016D01*
G01X103025Y1584775D02*
Y1589654D01*
G01Y1584775D02*
X97125D01*
G01X103025Y1589654D02*
X108121D01*
G01D02*
X109125Y1588650D01*
G01X51718Y1595562D02*
Y1665272D01*
G01X83200Y1588650D02*
X76781D01*
G01D02*
X75256Y1587125D01*
G01X89625Y1588650D02*
X83200D01*
G01X115750Y1662500D02*
X105800D01*
G01D02*
X103100Y1665200D01*
G01D02*
X94843D01*
G01D02*
X93462Y1663819D01*
G01D02*
X89764D01*
G01X62325Y1785025D02*
Y1715108D01*
G01D02*
X69000Y1708433D01*
G01D02*
Y1691709D01*
G01D02*
X72500Y1688209D01*
G01D02*
X78839D01*
G01X60150Y1785926D02*
Y1713150D01*
G01D02*
X66400Y1706900D01*
G01X78839Y1718209D02*
X72500D01*
G01D02*
X64500Y1726209D01*
G01X51718Y1665272D02*
X51635Y1665355D01*
G01X78839Y1683209D02*
X72500D01*
G01X120175Y1784743D02*
X111243Y1793675D01*
G01D02*
X70975D01*
G01D02*
X62325Y1785025D01*
G01X70424Y1796200D02*
X60150Y1785926D01*
G01X64500Y1726209D02*
Y1784000D01*
G01D02*
X71700Y1791200D01*
G01D02*
X110642D01*
G01D02*
X118000Y1783842D01*
G01X71015Y1738000D02*
Y1740286D01*
G01D02*
X71714Y1740985D01*
G01D02*
X70776Y1741923D01*
G01D02*
Y1743603D01*
G01D02*
X71307Y1744134D01*
G01D02*
X77205D01*
G01Y1740985D02*
X71714D01*
G01X93200Y1867400D02*
X97425Y1863175D01*
G01D02*
Y1853150D01*
G01X85640Y1847150D02*
Y1849172D01*
G01D02*
X87711Y1851243D01*
G01D02*
Y1858213D01*
G01D02*
X83467Y1862457D01*
G01X71475Y1852150D02*
Y1855775D01*
G01D02*
X72300Y1856600D01*
G01D02*
Y1866350D01*
G01D02*
X73100Y1867150D01*
G01X83467Y1862457D02*
X78774Y1867150D01*
G01X77100Y1846150D02*
X74550D01*
G01D02*
X71475Y1849225D01*
G01D02*
Y1852150D01*
G01X87850Y1836300D02*
Y1834300D01*
G01D02*
X89150Y1833000D01*
G01D02*
X102000D01*
G01D02*
X103900Y1831100D01*
G01D02*
Y1820200D01*
G01D02*
X101500Y1817800D01*
G01D02*
X85700D01*
G01D02*
X85000Y1817100D01*
G01X87850Y1840600D02*
Y1842977D01*
G01D02*
X88200Y1843327D01*
G01D02*
Y1847150D01*
G01X87850Y1840600D02*
Y1836300D01*
G01X74100Y1796200D02*
X70424D01*
G01X70060Y1837270D02*
X69936Y1837394D01*
G01D02*
X65806D01*
G01D02*
X65100Y1838100D01*
G01X70060Y1837270D02*
Y1832015D01*
G01D02*
X69960Y1831915D01*
G01X65100Y1838100D02*
Y1842150D01*
G01D02*
X67600Y1844650D01*
G01X93750Y1830000D02*
X89074D01*
G01D02*
X87674Y1831400D01*
G01D02*
X82964D01*
G01D02*
X80315D01*
G01D02*
X79800Y1831915D01*
G01D02*
X75710D01*
G01X90760Y1860311D02*
Y1853650D01*
G01X90749Y1860311D02*
X90760D01*
G01D02*
Y1862740D01*
G01D02*
X89600Y1863900D01*
G01D02*
X88350D01*
G01D02*
X84850Y1867400D01*
G01X88100Y1825000D02*
Y1827227D01*
G01D02*
X86612Y1828715D01*
G01D02*
X75710D01*
G01X93737Y1825915D02*
Y1821513D01*
G01D02*
X93750Y1821500D01*
G01D02*
X91600D01*
G01D02*
X88100Y1825000D01*
G01X105350Y1846300D02*
Y1849125D01*
G01D02*
X105175Y1849300D01*
G01D02*
Y1853150D01*
G01X105350Y1846300D02*
Y1839900D01*
G01X68225Y1823331D02*
Y1825681D01*
G01D02*
X69960Y1827416D01*
G01D02*
Y1828715D01*
G01X68225Y1823331D02*
X65969D01*
G01D02*
X62900Y1826400D01*
G01X101300Y1860650D02*
Y1862876D01*
G01D02*
X93074Y1871102D01*
G01X70160D02*
X61250Y1862192D01*
G01D02*
Y1828050D01*
G01D02*
X62900Y1826400D01*
G01X112144Y1795850D02*
X98550D01*
G01D02*
X93625Y1800775D01*
G01D02*
Y1802200D01*
G01X69225Y1859650D02*
Y1856625D01*
G01D02*
X67800Y1855200D01*
G01X79500Y1841400D02*
X77484Y1843416D01*
G01D02*
X73984D01*
G01D02*
X65250Y1852150D01*
G01D02*
X63725D01*
G01X84350Y1840600D02*
X82900D01*
G01D02*
X82100Y1841400D01*
G01D02*
X79500D01*
G01X101850Y1839900D02*
X97850D01*
G01X98000Y1848800D02*
X97850Y1848650D01*
G01D02*
Y1839900D01*
G01X93200Y1867400D02*
X88350D01*
G01X48000Y1880750D02*
Y1877500D01*
G01X78774Y1867150D02*
X73100D01*
G01X79500Y1934000D02*
X75000D01*
G01D02*
X73750Y1932750D01*
G01D02*
X69500D01*
G01X65500D02*
X69500D01*
G01X61000D02*
X65500D01*
G01X54500Y1939500D02*
Y1934000D01*
G01D02*
X55750Y1932750D01*
G01D02*
X61000D01*
G01X93074Y1871102D02*
X70160D01*
G01X60500Y1941100D02*
Y1936750D01*
G01D02*
X61000Y1936250D01*
G01X52000Y1880750D02*
Y1877500D01*
G01Y1880750D02*
X56000D01*
G01X48000Y1884250D02*
Y1886633D01*
G01D02*
X46868Y1887765D01*
G01X113500Y1875970D02*
X110195D01*
G01D02*
X99659Y1886506D01*
G01D02*
X83911D01*
G01D02*
X61555D01*
G01D02*
X60897Y1885848D01*
G01X41800Y1964050D02*
X50850D01*
G01D02*
X56600Y1958300D01*
G01D02*
X65325D01*
G01D02*
X69375Y1954250D01*
G01X60500Y1941100D02*
X62900D01*
G01D02*
X63500Y1940500D01*
G01D02*
X65750D01*
G01X54500Y1948500D02*
X63750D01*
G01D02*
X65500Y1946750D01*
G01D02*
X65750Y1946500D01*
G01D02*
Y1940500D01*
G01X55350Y1965300D02*
X61050D01*
G01X60600Y1970300D02*
X62600D01*
G01D02*
X63825Y1969075D01*
G01D02*
X66950D01*
G01X60600Y1970300D02*
Y1967250D01*
G01D02*
X61050Y1966800D01*
G01D02*
Y1965300D01*
G01X40825Y1970275D02*
X41700Y1969400D01*
G01X47850Y1969175D02*
X41925D01*
G01D02*
X41700Y1969400D01*
G01X180850Y27600D02*
X186750D01*
G01X180850D02*
Y22721D01*
G01D02*
X175754D01*
G01D02*
X174750Y23725D01*
G01X112800Y49200D02*
X118500D01*
G01D02*
X119850Y47850D01*
G01D02*
X121600D01*
G01D02*
X125700D01*
G01X118383Y123372D02*
X122272Y119483D01*
G01D02*
X239983D01*
G01X154875Y156250D02*
Y160500D01*
G01X124625Y162533D02*
Y141900D01*
G01D02*
X120600Y137875D01*
G01D02*
Y124232D01*
G01D02*
X123174Y121658D01*
G01D02*
X239082D01*
G01X146400Y136250D02*
X150557D01*
G01D02*
X155750D01*
G01D02*
X157953Y138453D01*
G01D02*
X162904D01*
G01X146400Y136250D02*
X130750D01*
G01D02*
X126800Y140200D01*
G01D02*
Y163700D01*
G01X122450Y161033D02*
Y142801D01*
G01D02*
X118383Y138734D01*
G01D02*
Y123372D01*
G01X155421Y142657D02*
X151000Y147078D01*
G01D02*
Y148750D01*
G01X132625Y162475D02*
Y148750D01*
G01X151000D02*
X147750Y152000D01*
G01D02*
X137700D01*
G01D02*
X134450Y148750D01*
G01D02*
X132625D01*
G01X162904Y141013D02*
X157065D01*
G01D02*
X155421Y142657D01*
G01X181404Y147453D02*
Y142546D01*
G01X186644Y138400D02*
X182526D01*
G01D02*
X181404Y139522D01*
G01D02*
Y142546D01*
G01X167606Y168811D02*
X163897D01*
G01D02*
X158497Y163411D01*
G01D02*
X145511D01*
G01D02*
X138350Y156250D01*
G01D02*
X136500D01*
G01X168385Y163411D02*
Y168032D01*
G01D02*
X167606Y168811D01*
G01X182582Y135000D02*
X190250D01*
G01X169404Y135893D02*
X172707D01*
G01D02*
X173600Y135000D01*
G01D02*
X182582D01*
G01X175400Y152000D02*
X172969D01*
G01D02*
X172172Y151203D01*
G01D02*
X170402D01*
G01X175400Y152000D02*
X177004D01*
G01D02*
X177904Y151100D01*
G01D02*
Y147453D01*
G01X170402Y151203D02*
X167298D01*
G01X181387Y158953D02*
X185304D01*
G01X174135Y160211D02*
X177289D01*
G01D02*
X178547Y158953D01*
G01D02*
X181387D01*
G01X174135Y163411D02*
X185445D01*
G01X146400Y139750D02*
X142250D01*
G01D02*
X141500Y140500D01*
G01X140375Y148750D02*
Y141625D01*
G01D02*
X141500Y140500D01*
G01X187608Y154749D02*
X164031D01*
G01D02*
X163994Y154786D01*
G01X168385Y160211D02*
X163414D01*
G01D02*
X162054Y158851D01*
G01D02*
Y156726D01*
G01D02*
X163994Y154786D01*
G01X114579Y137775D02*
Y140322D01*
G01D02*
X118832Y144575D01*
G01D02*
Y152559D01*
G01Y161575D02*
Y152559D01*
G01X129000Y255500D02*
X116100D01*
G01X171595Y273917D02*
X184500Y261012D01*
G01X117576Y258000D02*
X137700D01*
G01D02*
X143600Y252100D01*
G01X166890Y247992D02*
X171492D01*
G01D02*
X172900Y249400D01*
G01X166890Y251141D02*
X171159D01*
G01D02*
X172900Y249400D01*
G01X114295Y331567D02*
X120370D01*
G01X126445D02*
X120370D01*
G01X126445D02*
X128433D01*
G01D02*
X130400Y329600D01*
G01D02*
X138800D01*
G01D02*
X141600Y326800D01*
G01D02*
X148800D01*
G01D02*
X150307Y328307D01*
G01D02*
X154331D01*
G01X186717Y288795D02*
X171595Y303917D01*
G01D02*
X165256D01*
G01Y308917D02*
X171595D01*
G01X165256Y273917D02*
X171595D01*
G01X113650Y378779D02*
X118746D01*
G01D02*
X119750Y377775D01*
G01X113650Y373900D02*
Y378779D01*
G01X142725Y412850D02*
X139625Y409750D01*
G01D02*
Y403625D01*
G01D02*
X140875Y402375D01*
G01D02*
X149125D01*
G01X158200Y397350D02*
X160839Y399989D01*
G01D02*
Y405661D01*
G01D02*
X158500Y408000D01*
G01X158200Y397350D02*
Y398700D01*
G01D02*
X154525Y402375D01*
G01D02*
X153625D01*
G01D02*
X149125D01*
G01X129975Y401225D02*
X135875D01*
G01X129975D02*
Y396346D01*
G01D02*
X124879D01*
G01D02*
X123875Y397350D01*
G01X154700D02*
X149800D01*
G01X143375D02*
X149800D01*
G01X148400Y420350D02*
Y423850D01*
G01D02*
X148150Y424100D01*
G01D02*
Y426600D01*
G01X153400Y426000D02*
X151000D01*
G01D02*
X150400Y426600D01*
G01D02*
X148150D01*
G01X153400Y426000D02*
Y430350D01*
G01D02*
X152900Y430850D01*
G01X159400Y418600D02*
X150150D01*
G01D02*
X148400Y420350D01*
G01X144525Y412850D02*
X142725D01*
G01X144400Y434350D02*
X142150D01*
G01D02*
X140900Y433100D01*
G01D02*
X136900D01*
G01X148400Y434350D02*
X144400D01*
G01X152900D02*
X148400D01*
G01X159400Y427600D02*
Y433100D01*
G01D02*
X158150Y434350D01*
G01D02*
X152900D01*
G01X115800Y444600D02*
X120750D01*
G01D02*
X120800Y444550D01*
G01D02*
X125300D01*
G01X114300Y446100D02*
X115800Y444600D01*
G01X116782Y569642D02*
Y530500D01*
G01D02*
X154929Y492353D01*
G01D02*
X320703D01*
G01X186973Y542027D02*
X181318D01*
G01X141321Y541250D02*
X135250D01*
G01D02*
X129375Y547125D01*
G01D02*
Y556250D01*
G01X150000Y541250D02*
X141321D01*
G01X154500Y536000D02*
X158599D01*
G01D02*
X160000Y537401D01*
G01D02*
Y541000D01*
G01D02*
X161027Y542027D01*
G01D02*
X165138D01*
G01X121625Y556250D02*
Y566178D01*
G01Y556250D02*
X121775Y556400D01*
G01D02*
X123400D01*
G01D02*
X126900Y559900D01*
G01X136350D02*
X140000Y556250D01*
G01X144750Y549500D02*
X141500D01*
G01D02*
X140200Y550800D01*
G01D02*
Y556050D01*
G01D02*
X140000Y556250D01*
G01X150940Y556750D02*
Y550940D01*
G01D02*
X149500Y549500D01*
G01D02*
X144750D01*
G01X154500Y544750D02*
X157750D01*
G01X153500Y556750D02*
Y550000D01*
G01D02*
X150000Y546500D01*
G01D02*
Y544750D01*
G01X154500D02*
X150000D01*
G01X167250Y556330D02*
X164070D01*
G01D02*
X162300Y558100D01*
G01X170750Y556330D02*
X172815D01*
G01D02*
X172823Y556338D01*
G01D02*
X178427D01*
G01D02*
X178435Y556330D01*
G01D02*
X179565D01*
G01D02*
X179573Y556338D01*
G01D02*
X185677D01*
G01X181318Y539467D02*
X184533D01*
G01X181318Y544587D02*
X190413D01*
G01X321132Y495000D02*
X155358D01*
G01D02*
X118957Y531401D01*
G01D02*
Y570543D01*
G01X143875Y563750D02*
Y567375D01*
G01D02*
X150850Y574350D01*
G01X135000Y570000D02*
X142500Y577500D01*
G01D02*
X159929D01*
G01D02*
X162144Y575285D01*
G01X168385Y568923D02*
Y572332D01*
G01D02*
X165432Y575285D01*
G01D02*
X162144D01*
G01X135000Y570000D02*
X129500D01*
G01D02*
X125500Y566000D01*
G01D02*
Y563750D01*
G01X188900Y582800D02*
X184100Y578000D01*
G01D02*
X168428D01*
G01D02*
X148090Y598338D01*
G01D02*
X128590D01*
G01X184000Y667024D02*
Y619186D01*
G01D02*
X288404Y514782D01*
G01X121625Y566178D02*
X122025Y566578D01*
G01D02*
Y569625D01*
G01X126900Y559900D02*
X136350D01*
G01X156060Y563250D02*
X159250D01*
G01D02*
X162300Y560200D01*
G01D02*
Y558100D01*
G01X189000Y564465D02*
X181387D01*
G01X174135Y565723D02*
X177500D01*
G01D02*
X178758Y564465D01*
G01D02*
X181387D01*
G01X186084Y560416D02*
X170745D01*
G01D02*
X170055Y561106D01*
G01D02*
Y562264D01*
G01D02*
X168385Y563934D01*
G01D02*
Y565723D01*
G01X118957Y570543D02*
X113274Y576226D01*
G01D02*
Y576227D01*
G01D02*
X112000Y577501D01*
G01X174135Y568923D02*
X185445D01*
G01X166890Y653504D02*
X171304D01*
G01D02*
X173000Y655200D01*
G01X166890Y656653D02*
X171547D01*
G01D02*
X173000Y655200D01*
G01X171595Y709429D02*
X186175Y694849D01*
G01X165256Y679429D02*
X171595D01*
G01D02*
X184000Y667024D01*
G01X165256Y714429D02*
X171595D01*
G01X165256Y709429D02*
X171595D01*
G01X154331Y733819D02*
X150940D01*
G01D02*
X149521Y732400D01*
G01D02*
X142400D01*
G01D02*
X139700Y735100D01*
G01D02*
X130600D01*
G01D02*
X128600Y737100D01*
G01D02*
X127500D01*
G01X117945Y737167D02*
X122445D01*
G01D02*
X127433D01*
G01D02*
X127500Y737100D01*
G01X113650Y784279D02*
X118746D01*
G01D02*
X119750Y783275D01*
G01X113650Y779400D02*
Y784279D01*
G01X130350Y807100D02*
X136250D01*
G01X130350D02*
Y802221D01*
G01D02*
X125254D01*
G01D02*
X124250Y803225D01*
G01X159400Y824100D02*
X150150D01*
G01D02*
X148400Y825850D01*
G01D02*
X148150Y826100D01*
G01D02*
Y832100D01*
G01X153400Y831100D02*
Y835850D01*
G01D02*
X152900Y836350D01*
G01X148150Y832100D02*
X150400D01*
G01D02*
X151400Y831100D01*
G01D02*
X153400D01*
G01X144400Y839850D02*
X142150D01*
G01D02*
X140900Y838600D01*
G01D02*
X136900D01*
G01X159400Y833100D02*
Y838600D01*
G01D02*
X158150Y839850D01*
G01D02*
X152900D01*
G01D02*
X148400D01*
G01D02*
X144400D01*
G01X158500Y804250D02*
X155525D01*
G01D02*
X154500Y803225D01*
G01D02*
X150175D01*
G01X143750D02*
X150175D01*
G01X248000Y813500D02*
X183000D01*
G01D02*
X161600Y792100D01*
G01X144525Y818350D02*
X142725D01*
G01D02*
X140000Y815625D01*
G01D02*
Y809500D01*
G01D02*
X142100Y807400D01*
G01D02*
X143800D01*
G01X149500Y808250D02*
X148650Y807400D01*
G01D02*
X143800D01*
G01X158500Y807750D02*
X156500D01*
G01D02*
X156000Y808250D01*
G01D02*
X154000D01*
G01X149500D02*
X154000D01*
G01X122251Y848996D02*
X117404D01*
G01D02*
X117000Y849400D01*
G01D02*
X114900Y851500D01*
G01X122251Y848996D02*
X126746D01*
G01D02*
X126800Y849050D01*
G01X168385Y974435D02*
Y979624D01*
G01D02*
X168280Y979729D01*
G01X150000Y955000D02*
X156962Y948038D01*
G01D02*
X174962D01*
G01D02*
X182900Y940100D01*
G01D02*
X217100D01*
G01X150000Y955000D02*
X147478D01*
G01D02*
X143520Y958958D01*
G01D02*
Y971222D01*
G01D02*
X155860Y983562D01*
G01D02*
X165727D01*
G01D02*
X168280Y981009D01*
G01D02*
Y979729D01*
G01X166167Y960000D02*
Y962572D01*
G01D02*
X164984Y963755D01*
G01D02*
X161512D01*
G01X155375Y963750D02*
X161507D01*
G01D02*
X161512Y963755D01*
G01X176750Y963500D02*
X172977D01*
G01D02*
X171477Y965000D01*
G01D02*
X169477Y967000D01*
G01D02*
X152600D01*
G01D02*
X149350Y963750D01*
G01D02*
X147625D01*
G01X156996Y976999D02*
X157574Y976421D01*
G01D02*
Y974902D01*
G01D02*
X161226Y971250D01*
G01X156996Y976999D02*
X154325D01*
G01D02*
X151500Y974174D01*
G01D02*
Y971250D01*
G01X161226D02*
X161241Y971235D01*
G01D02*
X168385D01*
G01X191000Y964300D02*
X181050D01*
G01D02*
X180250Y963500D01*
G01X164299Y926325D02*
X319491D01*
G01X183838Y968275D02*
X188275D01*
G01X183838D02*
X180725D01*
G01D02*
X177765Y971235D01*
G01D02*
X174135D01*
G01X172705Y952750D02*
X170500D01*
G01D02*
X169667Y953583D01*
G01D02*
Y960000D01*
G01X174500D02*
X169667D01*
G01X178000Y952750D02*
X172705D01*
G01X174135Y974435D02*
X179000D01*
G01D02*
X180042Y975477D01*
G01D02*
X186487D01*
G01X165200Y928500D02*
X320650D01*
G01X137500Y1014500D02*
X134000D01*
G01X166890Y1059016D02*
X171616D01*
G01D02*
X173000Y1060400D01*
G01X166890Y1062165D02*
X171235D01*
G01D02*
X173000Y1060400D01*
G01X165256Y1084941D02*
X171595D01*
G01D02*
X184591Y1071945D01*
G01X165256Y1119941D02*
X171595D01*
G01X165256Y1114941D02*
X171595D01*
G01D02*
X186766Y1099770D01*
G01X137800Y1140700D02*
X140500Y1138000D01*
G01D02*
X148800D01*
G01D02*
X150131Y1139331D01*
G01X130350Y1212600D02*
Y1207721D01*
G01D02*
X125254D01*
G01D02*
X124250Y1208725D01*
G01X163170Y1210999D02*
X160896Y1208725D01*
G01D02*
X158575D01*
G01D02*
Y1210799D01*
G01D02*
X155624Y1213750D01*
G01X113650Y1189779D02*
X118746D01*
G01D02*
X119750Y1188775D01*
G01X113650Y1184900D02*
Y1189779D01*
G01X143750Y1208725D02*
X150175D01*
G01X155075D02*
X150175D01*
G01X122400Y1142550D02*
X127450D01*
G01D02*
X127500Y1142500D01*
G01D02*
X129300Y1140700D01*
G01D02*
X137800D01*
G01X150131Y1139331D02*
X154331D01*
G01X122400Y1142550D02*
X117900D01*
G01X130350Y1212600D02*
X136250D01*
G01X148700Y1245350D02*
X144700D01*
G01X153200D02*
X148700D01*
G01X159700Y1238600D02*
Y1244100D01*
G01D02*
X158450Y1245350D01*
G01D02*
X153200D01*
G01X137200Y1244100D02*
X141100D01*
G01D02*
X142350Y1245350D01*
G01D02*
X144700D01*
G01X144825Y1223850D02*
X142725D01*
G01D02*
X140000Y1221125D01*
G01D02*
Y1215000D01*
G01D02*
X141250Y1213750D01*
G01D02*
X149500D01*
G01X155624D02*
X154000D01*
G01D02*
X149500D01*
G01X121500Y1255550D02*
X116350D01*
G01D02*
X116300Y1255500D01*
G01X114900Y1256900D02*
X116300Y1255500D01*
G01X121500Y1255550D02*
X126000D01*
G01X148700Y1231350D02*
Y1231950D01*
G01D02*
X148450Y1232200D01*
G01D02*
Y1237600D01*
G01X153700Y1237000D02*
X151300D01*
G01D02*
X150700Y1237600D01*
G01D02*
X148450D01*
G01X153700Y1237000D02*
Y1241350D01*
G01D02*
X153200Y1241850D01*
G01X159700Y1229600D02*
X150450D01*
G01D02*
X148700Y1231350D01*
G01X169404Y1351428D02*
X173572D01*
G01D02*
X178400Y1346600D01*
G01D02*
X186100D01*
G01X120158Y1377918D02*
Y1339842D01*
G01D02*
X133856Y1326144D01*
G01D02*
X291488D01*
G01X154709Y1352302D02*
Y1347802D01*
G01Y1352302D02*
X157814D01*
G01D02*
X159500Y1353988D01*
G01D02*
X162904D01*
G01X154709Y1347802D02*
Y1344513D01*
G01X117983Y1377017D02*
Y1338941D01*
G01D02*
X132955Y1323969D01*
G01D02*
X290587D01*
G01X187779Y1354000D02*
X182000D01*
G01D02*
X181404Y1354596D01*
G01D02*
Y1357558D01*
G01X162904Y1356548D02*
X156287D01*
G01D02*
X155000Y1357835D01*
G01X151209Y1352302D02*
X145698D01*
G01D02*
X144375Y1353625D01*
G01D02*
Y1357194D01*
G01D02*
Y1364285D01*
G01X167624Y1385323D02*
X163874D01*
G01D02*
X158497Y1379946D01*
G01X168385D02*
Y1384562D01*
G01D02*
X167624Y1385323D01*
G01X158497Y1379946D02*
X148661D01*
G01D02*
X140500Y1371785D01*
G01X186750Y1382000D02*
X184000D01*
G01D02*
X183600Y1382400D01*
G01D02*
X181500D01*
G01X174135Y1379946D02*
X176446D01*
G01D02*
X178900Y1382400D01*
G01D02*
X181500D01*
G01X185000Y1373000D02*
X183200Y1374800D01*
G01D02*
X181300D01*
G01X174135Y1376746D02*
X176754D01*
G01D02*
X178700Y1374800D01*
G01D02*
X181300D01*
G01X181404Y1362488D02*
Y1357558D01*
G01X136625Y1378010D02*
Y1364285D01*
G01D02*
X139940Y1367600D01*
G01D02*
X151685D01*
G01D02*
X155000Y1364285D01*
G01D02*
Y1357835D01*
G01X158875Y1371785D02*
Y1376100D01*
G01X164066Y1371577D02*
X169077D01*
G01D02*
X169100Y1371600D01*
G01X164066Y1371577D02*
Y1375490D01*
G01D02*
X165322Y1376746D01*
G01D02*
X168385D01*
G01X169100Y1371600D02*
X170800Y1369900D01*
G01D02*
X187700D01*
G01X177904Y1362488D02*
Y1366150D01*
G01D02*
X176895Y1367159D01*
G01D02*
X175554D01*
G01X170402Y1366738D02*
X173154D01*
G01D02*
X173575Y1367159D01*
G01D02*
X175554D01*
G01X170402Y1366738D02*
X167401D01*
G01D02*
X167301Y1366838D01*
G01X165256Y1490453D02*
X171595D01*
G01D02*
X183825Y1478223D01*
G01D02*
Y1430384D01*
G01D02*
X259360Y1354849D01*
G01X166890Y1464528D02*
X171328D01*
G01D02*
X173100Y1466300D01*
G01X166890Y1467677D02*
X171723D01*
G01D02*
X173100Y1466300D01*
G01X111837Y1463453D02*
X135114D01*
G01D02*
X140413Y1468752D01*
G01D02*
X148095D01*
G01X130000Y1476750D02*
X126000D01*
G01X130000D02*
Y1482000D01*
G01D02*
Y1483500D01*
G01D02*
X130137Y1483637D01*
G01D02*
Y1488286D01*
G01Y1493406D02*
X125406D01*
G01D02*
X114000Y1482000D01*
G01Y1476750D02*
Y1482000D01*
G01X122000D02*
Y1476750D01*
G01D02*
X118000D01*
G01X122000Y1482000D02*
Y1485500D01*
G01D02*
X127346Y1490846D01*
G01D02*
X130137D01*
G01X112550Y1548200D02*
Y1543700D01*
G01Y1548200D02*
X118100D01*
G01D02*
X118900Y1547400D01*
G01D02*
X122500D01*
G01X154331Y1544843D02*
X149942D01*
G01D02*
X148632Y1543533D01*
G01D02*
X141567D01*
G01D02*
X139100Y1546000D01*
G01D02*
X129000D01*
G01D02*
X127600Y1547400D01*
G01D02*
X122500D01*
G01X186000Y1506048D02*
X171595Y1520453D01*
G01D02*
X165256D01*
G01Y1525453D02*
X171595D01*
G01X160900Y1635100D02*
X157000D01*
G01D02*
X155250Y1636850D01*
G01D02*
X149900D01*
G01X154900Y1642500D02*
X152500D01*
G01D02*
X151900Y1643100D01*
G01D02*
X149650D01*
G01X154900Y1642500D02*
Y1646850D01*
G01D02*
X154400Y1647350D01*
G01X149650Y1643100D02*
Y1637100D01*
G01D02*
X149900Y1636850D01*
G01X155075Y1614225D02*
X150175D01*
G01X143750D02*
X150175D01*
G01X158575D02*
X154350Y1610000D01*
G01X149500Y1619250D02*
X154000D01*
G01X158575Y1614225D02*
Y1616299D01*
G01D02*
X155624Y1619250D01*
G01D02*
X154000D01*
G01X146025Y1629350D02*
X142725D01*
G01D02*
X140000Y1626625D01*
G01D02*
Y1620500D01*
G01D02*
X141250Y1619250D01*
G01D02*
X149500D01*
G01X160900Y1644100D02*
Y1649600D01*
G01X130350Y1619100D02*
X132588D01*
G01D02*
X133588Y1618100D01*
G01D02*
X136250D01*
G01X130350Y1613221D02*
Y1619100D01*
G01Y1613221D02*
X125254D01*
G01D02*
X124250Y1614225D01*
G01X121950Y1661250D02*
X117000D01*
G01X121950D02*
X126900D01*
G01X117000D02*
X115750Y1662500D01*
G01X208500Y1634000D02*
X120175Y1722325D01*
G01X118000Y1721424D02*
X207642Y1631782D01*
G01X138400Y1649600D02*
X141900D01*
G01D02*
X143150Y1650850D01*
G01D02*
X145900D01*
G01X149900D02*
X145900D01*
G01X154400D02*
X149900D01*
G01X160900Y1649600D02*
X159650Y1650850D01*
G01D02*
X154400D01*
G01X120175Y1722325D02*
Y1784743D01*
G01X118000Y1783842D02*
Y1721424D01*
G01X175000Y1774500D02*
X173773Y1773273D01*
G01D02*
Y1771466D01*
G01D02*
X178423Y1766816D01*
G01D02*
X182692D01*
G01D02*
X188096Y1761412D01*
G01X181596Y1774500D02*
X175000D01*
G01X170080Y1773478D02*
X165522D01*
G01D02*
X165000Y1774000D01*
G01X168385Y1782258D02*
X164158D01*
G01D02*
X162800Y1780900D01*
G01D02*
Y1776200D01*
G01D02*
X165000Y1774000D01*
G01X170080Y1773478D02*
X171554Y1772004D01*
G01D02*
Y1767870D01*
G01D02*
X175924Y1763500D01*
G01D02*
X180596D01*
G01X186400Y1786700D02*
X179242D01*
G01D02*
X179042Y1786500D01*
G01D02*
X178000Y1785458D01*
G01D02*
X174135D01*
G01X157898Y1780145D02*
Y1788144D01*
G01D02*
X163284Y1793530D01*
G01D02*
X199470D01*
G01X140300Y1724100D02*
X143500Y1727300D01*
G01D02*
Y1747857D01*
G01D02*
X122350Y1769007D01*
G01D02*
Y1785644D01*
G01D02*
X112144Y1795850D01*
G01X167442Y1790692D02*
X164199D01*
G01D02*
X160625Y1787118D01*
G01D02*
Y1774875D01*
G01D02*
X171506Y1763994D01*
G01X168385Y1785458D02*
Y1789749D01*
G01D02*
X167442Y1790692D01*
G01X186500Y1749000D02*
X171506Y1763994D01*
G01X185500Y1781000D02*
X181387D01*
G01X174135Y1782258D02*
X177000D01*
G01D02*
X178258Y1781000D01*
G01D02*
X181387D01*
G01X186168Y1854114D02*
X183464Y1856818D01*
G01D02*
Y1884096D01*
G01X165256Y1930965D02*
X171595D01*
G01X185639Y1911921D02*
X171595Y1925965D01*
G01D02*
X165256D01*
G01X183464Y1884096D02*
X171595Y1895965D01*
G01D02*
X165256D01*
G01X166890Y1870040D02*
X171840D01*
G01D02*
X173500Y1871700D01*
G01X166890Y1873189D02*
X172011D01*
G01D02*
X173500Y1871700D01*
G01X122450Y1943900D02*
X126350D01*
G01D02*
X126500Y1943750D01*
G01D02*
X135850D01*
G01D02*
X138100Y1946000D01*
G01X154331Y1950355D02*
X148755D01*
G01D02*
X147600Y1949200D01*
G01D02*
X141300D01*
G01D02*
X138100Y1946000D01*
G01X208000Y44500D02*
X198750D01*
G01D02*
X197000Y46250D01*
G01D02*
X196750Y46500D01*
G01D02*
Y52500D01*
G01X205575Y23725D02*
X200675D01*
G01X194250D02*
X200675D01*
G01X213244D02*
X209075D01*
G01D02*
Y25799D01*
G01D02*
X206124Y28750D01*
G01D02*
X204500D01*
G01D02*
X200000D01*
G01X193125Y38750D02*
X190500Y36125D01*
G01D02*
Y30000D01*
G01D02*
X191750Y28750D01*
G01D02*
X200000D01*
G01X239983Y119483D02*
X388250Y267750D01*
G01X201600Y51900D02*
X199600D01*
G01D02*
X199000Y52500D01*
G01D02*
X196750D01*
G01X201500Y56750D02*
X202000Y56250D01*
G01D02*
Y52300D01*
G01D02*
X201600Y51900D01*
G01X193000Y60250D02*
X190750D01*
G01D02*
X189500Y59000D01*
G01D02*
X185500D01*
G01X197000Y60250D02*
X193000D01*
G01X201500D02*
X197000D01*
G01X206750D02*
X201500D01*
G01X208000Y53500D02*
Y59000D01*
G01D02*
X206750Y60250D01*
G01X239082Y121658D02*
X380250Y262826D01*
G01X187625Y148250D02*
Y139381D01*
G01D02*
X186644Y138400D01*
G01X195375Y148250D02*
X201499D01*
G01D02*
X203154Y146595D01*
G01D02*
Y139453D01*
G01X193750Y135000D02*
X201920D01*
G01D02*
X203154Y136234D01*
G01D02*
Y139453D01*
G01X192250Y162500D02*
Y158000D01*
G01X185304Y158953D02*
X186257Y158000D01*
G01D02*
X192250D01*
G01X185445Y163411D02*
X186487Y164453D01*
G01X192250Y167000D02*
X189034D01*
G01D02*
X186487Y164453D01*
G01X191500Y140750D02*
Y153500D01*
G01D02*
X190251Y154749D01*
G01D02*
X187608D01*
G01X290664Y232909D02*
X190591D01*
G01D02*
X186717Y236783D01*
G01D02*
Y288795D01*
G01X184500Y261012D02*
Y235924D01*
G01D02*
X189690Y230734D01*
G01D02*
X291565D01*
G01X186175Y620087D02*
X289305Y516957D01*
G01X199000Y535250D02*
X203000D01*
G01X193750D02*
X186973Y542027D01*
G01X199000Y535250D02*
X193750D01*
G01X283228Y505017D02*
X205445Y582800D01*
G01X185677Y556338D02*
X185685Y556330D01*
G01D02*
X185870D01*
G01D02*
X187075Y555125D01*
G01D02*
X194000D01*
G01X209750D02*
X194000D01*
G01X199000Y527750D02*
X203000D01*
G01X184533Y539467D02*
X192000Y532000D01*
G01D02*
Y529750D01*
G01D02*
X194000Y527750D01*
G01X199000D02*
X194000D01*
G01X190413Y544587D02*
X191500Y543500D01*
G01D02*
X192250Y542750D01*
G01D02*
X199000D01*
G01D02*
X203000D01*
G01X206700Y575000D02*
X208100D01*
G01D02*
X209250Y573850D01*
G01D02*
Y569000D01*
G01X206700Y575000D02*
X204675D01*
G01D02*
X203750Y574075D01*
G01D02*
Y569000D01*
G01X186175Y694849D02*
Y620087D01*
G01X205445Y582800D02*
X188900D01*
G01X212750Y569000D02*
X215400D01*
G01D02*
X217200Y567200D01*
G01D02*
Y565700D01*
G01X209750Y562875D02*
X216200D01*
G01D02*
X217200Y563875D01*
G01D02*
Y565700D01*
G01X191750Y569000D02*
Y564500D01*
G01D02*
X189035D01*
G01D02*
X189000Y564465D01*
G01X187500Y559000D02*
X186084Y560416D01*
G01X202250Y559000D02*
X187500D01*
G01X185445Y568923D02*
X186487Y569965D01*
G01X191750Y573500D02*
X190022D01*
G01D02*
X186487Y569965D01*
G01X325750Y735750D02*
X248000Y813500D01*
G01X184591Y1023363D02*
X257436Y950518D01*
G01X217100Y940100D02*
X219500Y942500D01*
G01D02*
Y945227D01*
G01X203850Y960977D02*
X198400D01*
G01D02*
X195500Y958077D01*
G01D02*
Y954300D01*
G01D02*
X194200Y953000D01*
G01D02*
X190500D01*
G01D02*
X190000Y952500D01*
G01D02*
Y949750D01*
G01X203850Y960977D02*
Y965477D01*
G01X198900D02*
X203850D01*
G01X208875Y952727D02*
Y957200D01*
G01X192560Y956250D02*
Y962740D01*
G01D02*
X191000Y964300D01*
G01X192250Y974000D02*
Y969500D01*
G01X188275Y968275D02*
X189500Y969500D01*
G01D02*
X192250D01*
G01X212300Y961000D02*
X214300D01*
G01D02*
X215625Y959675D01*
G01D02*
Y952727D01*
G01X207350Y960977D02*
X212277D01*
G01D02*
X212300Y961000D01*
G01X192250Y978500D02*
X189227Y975477D01*
G01D02*
X186487D01*
G01X186766Y1024264D02*
X258218Y952812D01*
G01X229500Y953227D02*
X223875D01*
G01D02*
X223375Y952727D01*
G01D02*
X219648Y949000D01*
G01D02*
X215000D01*
G01D02*
X211227Y945227D01*
G01D02*
X205000D01*
G01X191500Y942500D02*
X202273D01*
G01D02*
X205000Y945227D01*
G01X187440Y949750D02*
Y943460D01*
G01D02*
X188400Y942500D01*
G01D02*
X191500D01*
G01X184591Y1071945D02*
Y1023363D01*
G01X186766Y1099770D02*
Y1024264D01*
G01X199900Y1346488D02*
X201200Y1347788D01*
G01D02*
Y1353400D01*
G01D02*
X196029Y1358571D01*
G01X194904Y1346488D02*
X199900D01*
G01X191404D02*
X186212D01*
G01D02*
X186100Y1346600D01*
G01X188279Y1361238D02*
Y1354500D01*
G01D02*
X187779Y1354000D01*
G01X192154Y1365446D02*
Y1353738D01*
G01X196029Y1358571D02*
Y1361238D01*
G01X186750Y1373000D02*
X185000D01*
G01X186750Y1377500D02*
Y1373000D01*
G01X260218Y1357067D02*
X186000Y1431285D01*
G01X187700Y1369900D02*
X192154Y1365446D01*
G01X186000Y1431285D02*
Y1506048D01*
G01X342650Y1634000D02*
X208500D01*
G01X207642Y1631782D02*
X348532D01*
G01X224875Y1763750D02*
Y1768100D01*
G01X185096Y1774500D02*
X186374D01*
G01D02*
X188477Y1776603D01*
G01D02*
X190266D01*
G01D02*
X195782D01*
G01D02*
X197825Y1774560D01*
G01D02*
X201096D01*
G01X244850Y1769900D02*
X241089D01*
G01D02*
X239375Y1768186D01*
G01D02*
Y1763750D01*
G01X207596Y1769440D02*
Y1764304D01*
G01D02*
X210500Y1761400D01*
G01X221000Y1756250D02*
X215650D01*
G01D02*
X210500Y1761400D01*
G01X239375Y1763750D02*
X235725Y1760100D01*
G01D02*
X231600D01*
G01D02*
X227750Y1756250D01*
G01D02*
X221000D01*
G01X200198Y1758750D02*
X202299D01*
G01D02*
X203299Y1759750D01*
G01X200198Y1758750D02*
Y1756711D01*
G01D02*
X201447Y1755462D01*
G01D02*
Y1751500D01*
G01X194750Y1753000D02*
X196304D01*
G01D02*
X197804Y1751500D01*
G01D02*
X201447D01*
G01X228181Y1772100D02*
X230444D01*
G01D02*
X231625Y1770919D01*
G01D02*
Y1763750D01*
G01X219450Y1772100D02*
X228181D01*
G01X188096Y1761412D02*
Y1759625D01*
G01Y1767375D02*
X190967D01*
G01D02*
X194750Y1763592D01*
G01D02*
Y1762000D01*
G01Y1756500D02*
Y1762000D01*
G01X186400Y1786700D02*
X187450D01*
G01D02*
X191250Y1790500D01*
G01X199470Y1793530D02*
X215950Y1777050D01*
G01D02*
Y1776200D01*
G01X207596Y1772000D02*
X215850D01*
G01D02*
X215950Y1772100D01*
G01Y1776200D02*
Y1772100D01*
G01X235500Y1756250D02*
X228250Y1749000D01*
G01D02*
X186500D01*
G01X191250Y1781500D02*
X186000D01*
G01D02*
X185500Y1781000D01*
G01X191250Y1786000D02*
Y1781500D01*
G01X280100Y1856289D02*
X187069D01*
G01D02*
X185639Y1857719D01*
G01D02*
Y1911921D01*
G01X279199Y1854114D02*
X186168D01*
G01X394718Y268973D02*
X292700Y166955D01*
G01D02*
X292600D01*
G01X344750Y286995D02*
X290664Y232909D01*
G01X291565Y230734D02*
X352750Y291919D01*
G01X320703Y492353D02*
X347250Y465806D01*
G01X328250Y417000D02*
Y413000D01*
G01D02*
X333500D01*
G01X328250Y421000D02*
X333500D01*
G01X289305Y516957D02*
X333543D01*
G01X291955Y505017D02*
X283228D01*
G01X297300D02*
X291955D01*
G01X288404Y514782D02*
X331968D01*
G01X352232Y463900D02*
X321132Y495000D01*
G01X325750Y605000D02*
X322000D01*
G01D02*
X315400Y598400D01*
G01D02*
X312600Y595600D01*
G01D02*
X311900D01*
G01D02*
X308100Y591800D01*
G01D02*
Y590421D01*
G01X325750Y593000D02*
Y589000D01*
G01X314000Y587000D02*
X311000D01*
G01D02*
X310484Y586484D01*
G01D02*
X307800D01*
G01X325750Y589000D02*
X322549D01*
G01D02*
X322149Y589400D01*
G01D02*
X316400D01*
G01D02*
X314000Y587000D01*
G01X325750Y597000D02*
X324900D01*
G01D02*
X320900Y593000D01*
G01X325750Y601000D02*
Y597000D01*
G01X320900Y593000D02*
X314923D01*
G01D02*
X311825Y589902D01*
G01D02*
Y589825D01*
G01D02*
X310453Y588453D01*
G01D02*
X307800D01*
G01X325750Y609000D02*
Y735750D01*
G01X329250Y609000D02*
Y605000D01*
G01D02*
X332500D01*
G01X306500Y568400D02*
X309150Y565750D01*
G01D02*
X313000D01*
G01X306500Y568400D02*
X304921Y569979D01*
G01D02*
Y577400D01*
G01X313000Y565750D02*
X317500D01*
G01X333500Y843000D02*
X328250D01*
G01D02*
Y847000D01*
G01Y851000D02*
X333500D01*
G01X319491Y926325D02*
X347250Y898566D01*
G01X320650Y928500D02*
X355250Y893900D01*
G01X257436Y950518D02*
X331151D01*
G01X258218Y952812D02*
X331933D01*
G01X328250Y1222500D02*
X333500D01*
G01X328250Y1218500D02*
Y1214500D01*
G01D02*
X333500D01*
G01X259360Y1354849D02*
X293651D01*
G01D02*
X382750Y1265750D01*
G01X291488Y1326144D02*
X351485Y1266147D01*
G01X290587Y1323969D02*
X347250Y1267306D01*
G01X385057Y1266519D02*
X294509Y1357067D01*
G01D02*
X260218D01*
G01X311500Y1395750D02*
Y1396700D01*
G01D02*
X307400Y1400800D01*
G01D02*
Y1406600D01*
G01D02*
X302953Y1411047D01*
G01D02*
Y1413700D01*
G01X311500Y1395750D02*
X315500D01*
G01X280250Y1407500D02*
X283304Y1410554D01*
G01D02*
X283454D01*
G01D02*
X285100Y1412200D01*
G01X291900Y1416579D02*
X289479D01*
G01D02*
X285100Y1412200D01*
G01X280250Y1403500D02*
Y1407500D01*
G01X319500Y1395750D02*
Y1400300D01*
G01D02*
X313500Y1406300D01*
G01D02*
X306400Y1413400D01*
G01D02*
X304921D01*
G01X319500Y1392250D02*
Y1389000D01*
G01X307500Y1395750D02*
X303500D01*
G01X301500Y1407500D02*
X303500Y1405500D01*
G01D02*
Y1395750D01*
G01X301500Y1407500D02*
Y1410500D01*
G01D02*
X300984Y1411016D01*
G01D02*
Y1413700D01*
G01X333500Y1713000D02*
X328250D01*
G01D02*
Y1717000D01*
G01Y1721000D02*
X333500D01*
G01X278280Y1774600D02*
Y1779180D01*
G01D02*
X279500Y1780400D01*
G01D02*
Y1783000D01*
G01X283500Y1788250D02*
X279500D01*
G01D02*
Y1783000D01*
G01X280840Y1774600D02*
Y1777840D01*
G01D02*
X282900Y1779900D01*
G01D02*
X284400D01*
G01D02*
X287500Y1783000D01*
G01X291500Y1788250D02*
X287500D01*
G01D02*
Y1783000D01*
G01X278280Y1752400D02*
Y1749220D01*
G01D02*
X282000Y1745500D01*
G01X280500Y1734750D02*
X281000Y1735250D01*
G01D02*
Y1744500D01*
G01D02*
X282000Y1745500D01*
G01X275720Y1774600D02*
Y1778780D01*
G01D02*
X271500Y1783000D01*
G01X275500Y1788250D02*
X271500D01*
G01Y1783000D02*
Y1788250D01*
G01X271000Y1745500D02*
Y1736250D01*
G01D02*
X272500Y1734750D01*
G01X273160Y1752400D02*
Y1747660D01*
G01D02*
X271000Y1745500D01*
G01X275720Y1752400D02*
Y1744280D01*
G01D02*
X276500Y1743500D01*
G01D02*
Y1740000D01*
G01Y1734750D02*
Y1740000D01*
G01X355250Y1781139D02*
X280100Y1856289D01*
G01X347250Y1786063D02*
X279199Y1854114D01*
G01X356530Y88350D02*
Y77470D01*
G01D02*
X358000Y76000D01*
G01Y70750D02*
Y76000D01*
G01X356530Y104650D02*
Y110470D01*
G01D02*
X355000Y112000D01*
G01X352500Y123750D02*
Y114500D01*
G01D02*
X355000Y112000D01*
G01X352500Y81500D02*
Y82435D01*
G01D02*
X354565Y84500D01*
G01D02*
Y88350D01*
G01X352500Y75250D02*
Y81500D01*
G01Y75250D02*
X348500D01*
G01X354565Y104650D02*
Y108499D01*
G01D02*
X348500Y114564D01*
G01D02*
Y118500D01*
G01Y123750D02*
Y118500D01*
G01X380250Y262826D02*
Y336100D01*
G01Y341000D02*
Y336100D01*
G01X388250Y341000D02*
Y336000D01*
G01Y267750D02*
Y336000D01*
G01X344750Y336100D02*
Y341000D01*
G01Y336100D02*
Y286995D01*
G01X394718Y345782D02*
Y268973D01*
G01X352750Y341000D02*
Y336000D01*
G01Y291919D02*
Y336000D01*
G01X353000Y348750D02*
Y352250D01*
G01D02*
X352750Y352500D01*
G01X349870Y348870D02*
X349990Y348750D01*
G01D02*
X353000D01*
G01X352750Y352500D02*
Y358250D01*
G01D02*
X350957Y360043D01*
G01D02*
Y368457D01*
G01D02*
X361140Y378640D01*
G01D02*
Y382585D01*
G01X406000Y402500D02*
X401750Y406750D01*
G01D02*
X398000D01*
G01X394000Y392000D02*
X404000D01*
G01X394000D02*
X392890Y393110D01*
G01D02*
X387415D01*
G01Y391140D02*
X393140D01*
G01D02*
X394000Y392000D01*
G01X392500Y406890D02*
X392000Y407390D01*
G01D02*
Y408000D01*
G01D02*
X391140Y408860D01*
G01D02*
X387415D01*
G01X392500Y406890D02*
X397860D01*
G01D02*
X398000Y406750D01*
G01X387415Y406890D02*
X392500D01*
G01X380500Y345250D02*
Y341250D01*
G01D02*
X380250Y341000D01*
G01X376890Y382585D02*
Y377940D01*
G01D02*
X383000Y371830D01*
G01D02*
Y359000D01*
G01D02*
X381500Y357500D01*
G01X380250Y352500D02*
Y356250D01*
G01D02*
X381500Y357500D01*
G01X380500Y348750D02*
Y352250D01*
G01D02*
X380250Y352500D01*
G01X337424Y413000D02*
X339086Y411338D01*
G01D02*
X345662D01*
G01D02*
X350110Y406890D01*
G01D02*
X352585D01*
G01X388500Y345250D02*
Y341250D01*
G01D02*
X388250Y341000D01*
G01X352585Y395080D02*
X349420D01*
G01D02*
X348500Y396000D01*
G01D02*
X346500D01*
G01D02*
X343500Y393000D01*
G01X338250Y389000D02*
Y393000D01*
G01D02*
X343500D01*
G01X345000Y345250D02*
Y341250D01*
G01D02*
X344750Y341000D01*
G01X345487Y413513D02*
X350140Y408860D01*
G01D02*
X352585D01*
G01X345900Y376000D02*
X344400Y374500D01*
G01D02*
X343000D01*
G01D02*
X341500Y373000D01*
G01D02*
X334250D01*
G01X352585Y389175D02*
X350175D01*
G01D02*
X348000Y387000D01*
G01D02*
Y378100D01*
G01D02*
X345900Y376000D01*
G01X334250Y377000D02*
Y373000D01*
G01X388500Y348750D02*
X391750D01*
G01D02*
X394718Y345782D01*
G01X388250Y352500D02*
Y358250D01*
G01D02*
X385175Y361325D01*
G01D02*
Y371655D01*
G01D02*
X378860Y377970D01*
G01D02*
Y382585D01*
G01X388250Y352500D02*
X388500Y352250D01*
G01D02*
Y348750D01*
G01X345000D02*
Y352250D01*
G01D02*
X344750Y352500D01*
G01X346000Y357500D02*
X344750Y356250D01*
G01D02*
Y352500D01*
G01X359175Y382585D02*
Y378675D01*
G01D02*
X348782Y368282D01*
G01D02*
Y360282D01*
G01D02*
X346000Y357500D01*
G01X353000Y345250D02*
Y341250D01*
G01D02*
X352750Y341000D01*
G01X355000Y451250D02*
Y447750D01*
G01D02*
X355250Y447500D01*
G01X354000Y442500D02*
X355250Y443750D01*
G01D02*
Y447500D01*
G01X361140Y417415D02*
Y421260D01*
G01D02*
X351218Y431182D01*
G01D02*
Y439718D01*
G01D02*
X354000Y442500D01*
G01X347250Y459000D02*
Y464000D01*
G01X347000Y454750D02*
Y458750D01*
G01D02*
X347250Y459000D01*
G01Y465806D02*
Y464000D01*
G01X333500Y413000D02*
X337424D01*
G01X390750Y459000D02*
Y463900D01*
G01X390500Y454750D02*
Y458750D01*
G01D02*
X390750Y459000D01*
G01X333543Y516957D02*
X386600Y463900D01*
G01D02*
X390750D01*
G01X382500Y451250D02*
X385589D01*
G01D02*
X385607Y451232D01*
G01X382750Y447500D02*
X382500Y447750D01*
G01D02*
Y451250D01*
G01X382750Y447500D02*
Y441650D01*
G01D02*
X384543Y439857D01*
G01D02*
Y430043D01*
G01D02*
X376890Y422390D01*
G01D02*
Y417415D01*
G01X347000Y451250D02*
Y447750D01*
G01D02*
X347250Y447500D01*
G01X350137Y451250D02*
X347000D01*
G01X347250Y447500D02*
Y442150D01*
G01D02*
X349000Y440400D01*
G01D02*
Y431400D01*
G01D02*
X349043Y431357D01*
G01D02*
Y430757D01*
G01D02*
X350976Y428824D01*
G01D02*
X351576D01*
G01D02*
X359175Y421225D01*
G01D02*
Y417415D01*
G01X382500Y454750D02*
Y458750D01*
G01D02*
X382750Y459000D01*
G01D02*
Y464000D01*
G01X331968Y514782D02*
X382750Y464000D01*
G01X333500Y421000D02*
X336500Y418000D01*
G01D02*
Y417000D01*
G01D02*
X339987Y413513D01*
G01D02*
X345487D01*
G01X390500Y451250D02*
Y447750D01*
G01D02*
X390750Y447500D01*
G01X389500Y442500D02*
X386718Y439718D01*
G01D02*
Y429998D01*
G01D02*
X378860Y422140D01*
G01D02*
Y417415D01*
G01X389500Y442500D02*
X390750Y443750D01*
G01D02*
Y447500D01*
G01X355250Y459000D02*
Y463900D01*
G01X355000Y454750D02*
Y458750D01*
G01D02*
X355250Y459000D01*
G01Y463900D02*
X352232D01*
G01X373750Y766100D02*
Y684618D01*
G01D02*
X860368Y198000D01*
G01X381750Y766000D02*
Y679694D01*
G01D02*
X861269Y200175D01*
G01X373750Y771000D02*
Y766100D01*
G01X374000Y775250D02*
Y771250D01*
G01D02*
X373750Y771000D01*
G01X382000Y775250D02*
Y771250D01*
G01D02*
X381750Y771000D01*
G01D02*
Y766000D01*
G01X410000Y813000D02*
X400280D01*
G01D02*
X392140Y821140D01*
G01D02*
X387415D01*
G01X361140Y847415D02*
Y851360D01*
G01X333500Y851000D02*
X336500Y848000D01*
G01D02*
Y846800D01*
G01D02*
X339787Y843513D01*
G01D02*
X345487D01*
G01D02*
X350140Y838860D01*
G01D02*
X352585D01*
G01X376890Y847415D02*
Y852390D01*
G01X359175Y812585D02*
Y809005D01*
G01D02*
X360100Y808080D01*
G01D02*
X361140Y809120D01*
G01D02*
Y812585D01*
G01X397250Y840500D02*
X394500D01*
G01D02*
X392500Y838500D01*
G01D02*
X391500D01*
G01D02*
X391140Y838860D01*
G01D02*
X387415D01*
G01X402000Y844000D02*
X401000D01*
G01D02*
X397500Y840500D01*
G01D02*
X397250D01*
G01X387415Y836890D02*
X391000D01*
G01D02*
X391500Y837390D01*
G01D02*
Y838500D01*
G01X373750Y782500D02*
Y786350D01*
G01D02*
X375100Y787700D01*
G01D02*
X376400Y789000D01*
G01D02*
Y802140D01*
G01D02*
X376890Y802630D01*
G01D02*
Y812585D01*
G01X374000Y778750D02*
Y782250D01*
G01D02*
X373750Y782500D01*
G01X338250Y819000D02*
Y823000D01*
G01D02*
X343500D01*
G01X352585Y825080D02*
X349420D01*
G01D02*
X348500Y826000D01*
G01D02*
X346500D01*
G01D02*
X343500Y823000D01*
G01X378860Y847415D02*
Y852140D01*
G01X382000Y778750D02*
X384834D01*
G01D02*
X385196Y779112D01*
G01X379600Y795300D02*
Y802900D01*
G01D02*
X378860Y803640D01*
G01D02*
Y812585D01*
G01X381750Y782500D02*
X382000Y782250D01*
G01D02*
Y778750D01*
G01X381750Y782500D02*
Y788750D01*
G01D02*
X379600Y790900D01*
G01D02*
Y795300D01*
G01X387415Y823110D02*
X392390D01*
G01D02*
X399825Y815675D01*
G01D02*
X410175D01*
G01X359175Y851325D02*
Y847415D01*
G01X345300Y804400D02*
X348000Y807100D01*
G01D02*
Y817000D01*
G01D02*
X350175Y819175D01*
G01D02*
X352585D01*
G01X345300Y804400D02*
X343900Y803000D01*
G01D02*
X334250D01*
G01Y807000D02*
Y803000D01*
G01X333500Y843000D02*
X337224D01*
G01D02*
X338886Y841338D01*
G01D02*
X345662D01*
G01D02*
X350110Y836890D01*
G01D02*
X352585D01*
G01X382500Y884750D02*
Y888750D01*
G01D02*
X382750Y889000D01*
G01Y894000D02*
Y889000D01*
G01X331151Y950518D02*
X382750Y898919D01*
G01D02*
Y894000D01*
G01X355000Y881250D02*
Y877750D01*
G01D02*
X355250Y877500D01*
G01X354000Y872500D02*
X355250Y873750D01*
G01D02*
Y877500D01*
G01X361140Y851360D02*
X351218Y861282D01*
G01D02*
Y869718D01*
G01D02*
X354000Y872500D01*
G01X382500Y881250D02*
X382750Y881000D01*
G01D02*
Y877500D01*
G01X379372Y880728D02*
X379894Y881250D01*
G01D02*
X382500D01*
G01X376890Y852390D02*
X384500Y860000D01*
G01D02*
Y870000D01*
G01D02*
X382750Y871750D01*
G01D02*
Y877500D01*
G01X390500Y881250D02*
Y877750D01*
G01D02*
X390750Y877500D01*
G01X389500Y872500D02*
X390750Y873750D01*
G01D02*
Y877500D01*
G01X378860Y852140D02*
X386675Y859955D01*
G01D02*
Y869675D01*
G01D02*
X389500Y872500D01*
G01X347000Y884750D02*
Y888750D01*
G01D02*
X347250Y889000D01*
G01Y894000D02*
Y889000D01*
G01Y898566D02*
Y894000D01*
G01X347000Y881250D02*
Y877750D01*
G01D02*
X347250Y877500D01*
G01X343894Y880707D02*
X344437Y881250D01*
G01D02*
X347000D01*
G01X347250Y877500D02*
Y870450D01*
G01D02*
X349000Y868700D01*
G01D02*
Y861500D01*
G01D02*
X359175Y851325D01*
G01X390500Y884750D02*
Y888750D01*
G01D02*
X390750Y889000D01*
G01Y893900D02*
Y889000D01*
G01X331933Y952812D02*
X390750Y893995D01*
G01D02*
Y893900D01*
G01X355000Y884750D02*
Y888750D01*
G01D02*
X355250Y889000D01*
G01Y893900D02*
Y889000D01*
G01X388250Y1137500D02*
Y1113750D01*
G01D02*
X490500Y1011500D01*
G01X388250Y1142500D02*
Y1137500D01*
G01X380250Y1137600D02*
Y1118674D01*
G01D02*
X489599Y1009325D01*
G01X380250Y1142500D02*
Y1137600D01*
G01X345487Y1215013D02*
X350140Y1210360D01*
G01D02*
X352585D01*
G01X397645Y1216675D02*
X391330Y1210360D01*
G01D02*
X387415D01*
G01X381500Y1159000D02*
X383200Y1160700D01*
G01D02*
Y1173030D01*
G01D02*
X376890Y1179340D01*
G01D02*
Y1184085D01*
G01X380250Y1154000D02*
Y1157750D01*
G01D02*
X381500Y1159000D01*
G01X380500Y1150250D02*
Y1153750D01*
G01D02*
X380250Y1154000D01*
G01X345662Y1212838D02*
X350110Y1208390D01*
G01D02*
X352585D01*
G01X388500Y1146750D02*
Y1142750D01*
G01D02*
X388250Y1142500D01*
G01X352585Y1190675D02*
X350175D01*
G01D02*
X348000Y1188500D01*
G01D02*
Y1178500D01*
G01D02*
X345600Y1176100D01*
G01X334250Y1174500D02*
X344000D01*
G01D02*
X345600Y1176100D01*
G01X334250Y1178500D02*
Y1174500D01*
G01X388500Y1150250D02*
X391900D01*
G01X388250Y1154000D02*
Y1160150D01*
G01D02*
X385900Y1162500D01*
G01D02*
Y1166100D01*
G01D02*
Y1172000D01*
G01D02*
X378860Y1179040D01*
G01D02*
Y1184085D01*
G01X388250Y1154000D02*
X388500Y1153750D01*
G01D02*
Y1150250D01*
G01X352585Y1196580D02*
X349420D01*
G01D02*
X348500Y1197500D01*
G01D02*
X346500D01*
G01D02*
X343500Y1194500D01*
G01D02*
X338250D01*
G01D02*
Y1190500D01*
G01X397470Y1214500D02*
X391360Y1208390D01*
G01D02*
X387415D01*
G01X361140Y1184085D02*
Y1181605D01*
G01D02*
X359175Y1179640D01*
G01X398750Y1192000D02*
Y1188250D01*
G01X387415Y1192640D02*
X391640D01*
G01D02*
X392500Y1193500D01*
G01D02*
X394000Y1192000D01*
G01D02*
X398750D01*
G01X387415Y1194610D02*
X391390D01*
G01D02*
X392500Y1193500D01*
G01X359175Y1184085D02*
Y1179640D01*
G01X380500Y1146750D02*
Y1142750D01*
G01D02*
X380250Y1142500D01*
G01X382500Y1256250D02*
Y1260250D01*
G01D02*
X382750Y1260500D01*
G01Y1265500D02*
Y1260500D01*
G01Y1265750D02*
Y1265500D01*
G01X347000Y1252750D02*
X347250Y1252500D01*
G01D02*
Y1249000D01*
G01X343822Y1252222D02*
X344350Y1252750D01*
G01D02*
X347000D01*
G01X359175Y1218915D02*
Y1222325D01*
G01D02*
X348500Y1233000D01*
G01D02*
Y1241796D01*
G01D02*
X347347Y1242949D01*
G01D02*
Y1248903D01*
G01D02*
X347250Y1249000D01*
G01X333500Y1222500D02*
X335300D01*
G01D02*
X336500Y1221300D01*
G01D02*
Y1218184D01*
G01D02*
X339671Y1215013D01*
G01D02*
X345487D01*
G01X355000Y1256250D02*
Y1260250D01*
G01D02*
X355250Y1260500D01*
G01D02*
Y1265181D01*
G01D02*
X355029Y1265402D01*
G01X351485Y1266147D02*
X354284D01*
G01D02*
X355029Y1265402D01*
G01X347000Y1256250D02*
Y1260250D01*
G01D02*
X347250Y1260500D01*
G01Y1265500D02*
Y1260500D01*
G01Y1267306D02*
Y1265500D01*
G01X408675Y1216675D02*
X397645D01*
G01X390500Y1252750D02*
Y1249250D01*
G01D02*
X390750Y1249000D01*
G01X378860Y1218915D02*
Y1223640D01*
G01D02*
X386500Y1231280D01*
G01D02*
Y1241000D01*
G01D02*
X389500Y1244000D01*
G01D02*
X390750Y1245250D01*
G01D02*
Y1249000D01*
G01X390500Y1256250D02*
Y1260250D01*
G01D02*
X390750Y1260500D01*
G01Y1265400D02*
Y1260500D01*
G01Y1265400D02*
X389631Y1266519D01*
G01D02*
X385057D01*
G01X333500Y1214500D02*
X337108D01*
G01D02*
X338770Y1212838D01*
G01D02*
X345662D01*
G01X382500Y1252750D02*
X379871D01*
G01D02*
X379395Y1252274D01*
G01X382750Y1249000D02*
X382500Y1249250D01*
G01D02*
Y1252750D01*
G01X382750Y1249000D02*
Y1243350D01*
G01D02*
X384282Y1241818D01*
G01D02*
Y1231282D01*
G01D02*
X376890Y1223890D01*
G01D02*
Y1218915D01*
G01X411000Y1214500D02*
X397470D01*
G01X355000Y1252750D02*
Y1249250D01*
G01D02*
X355250Y1249000D01*
G01X354000Y1244000D02*
X355250Y1245250D01*
G01D02*
Y1249000D01*
G01X361140Y1218915D02*
Y1222360D01*
G01D02*
X351000Y1232500D01*
G01D02*
Y1241000D01*
G01D02*
X354000Y1244000D01*
G01X344750Y1641000D02*
Y1636100D01*
G01X345000Y1645250D02*
Y1641250D01*
G01D02*
X344750Y1641000D01*
G01Y1636100D02*
X342650Y1634000D01*
G01X352750Y1641000D02*
Y1636000D01*
G01X353000Y1645250D02*
Y1641250D01*
G01D02*
X352750Y1641000D01*
G01X348532Y1631782D02*
X352750Y1636000D01*
G01X378860Y1725860D02*
Y1717415D01*
G01X376890Y1723890D02*
Y1717415D01*
G01X378860Y1682585D02*
Y1679970D01*
G01D02*
X376890Y1678000D01*
G01Y1682585D02*
Y1678000D01*
G01X395500Y1690500D02*
X394000Y1692000D01*
G01D02*
X392500D01*
G01D02*
X391640Y1691140D01*
G01D02*
X387415D01*
G01Y1693110D02*
X391390D01*
G01D02*
X392500Y1692000D01*
G01X348825Y1731175D02*
X359175Y1720825D01*
G01D02*
Y1717415D01*
G01X352585Y1695080D02*
X347680D01*
G01D02*
X346200Y1693600D01*
G01D02*
X344000D01*
G01D02*
X342300D01*
G01D02*
X340900Y1695000D01*
G01D02*
X338250D01*
G01Y1691000D02*
Y1695000D01*
G01X333500Y1713000D02*
X337224D01*
G01D02*
X338886Y1711338D01*
G01D02*
X345662D01*
G01D02*
X350110Y1706890D01*
G01D02*
X352585D01*
G01X333500Y1721000D02*
X336500Y1718000D01*
G01D02*
Y1716800D01*
G01D02*
X339787Y1713513D01*
G01D02*
X345487D01*
G01D02*
X350140Y1708860D01*
G01D02*
X352585D01*
G01X345000Y1648750D02*
Y1652250D01*
G01D02*
X344750Y1652500D01*
G01X346000Y1657500D02*
X348782Y1660282D01*
G01D02*
Y1667472D01*
G01D02*
X359175Y1677865D01*
G01D02*
Y1682585D01*
G01X346000Y1657500D02*
X344750Y1656250D01*
G01D02*
Y1652500D01*
G01X346000Y1676500D02*
X342000D01*
G01D02*
X338500Y1673000D01*
G01D02*
X334250D01*
G01D02*
Y1677000D01*
G01X346000Y1676500D02*
X348300Y1678800D01*
G01D02*
Y1687300D01*
G01D02*
X350175Y1689175D01*
G01D02*
X352585D01*
G01X361140Y1717415D02*
Y1720860D01*
G01D02*
X351000Y1731000D01*
G01X409525Y1715175D02*
X399175D01*
G01D02*
X392860Y1708860D01*
G01D02*
X387415D01*
G01X353000Y1648750D02*
X352750Y1649000D01*
G01D02*
Y1652500D01*
G01X361140Y1682585D02*
Y1678140D01*
G01D02*
X350957Y1667957D01*
G01D02*
Y1660043D01*
G01D02*
X352750Y1658250D01*
G01D02*
Y1652500D01*
G01X356174Y1649291D02*
X355633Y1648750D01*
G01D02*
X353000D01*
G01X387415Y1706890D02*
X392690D01*
G01D02*
X398800Y1713000D01*
G01D02*
X411000D01*
G01X379000Y1726000D02*
X378860Y1725860D01*
G01D02*
X376890Y1723890D01*
G01X379000Y1726000D02*
Y1729250D01*
G01X347000Y1751250D02*
X347250Y1751000D01*
G01D02*
Y1747500D01*
G01D02*
Y1743831D01*
G01D02*
X348825Y1742256D01*
G01D02*
Y1731175D01*
G01X343668Y1750741D02*
X344177Y1751250D01*
G01D02*
X347000D01*
G01X355000Y1754750D02*
Y1758750D01*
G01D02*
X355250Y1759000D01*
G01Y1763900D02*
Y1759000D01*
G01Y1763900D02*
Y1781139D01*
G01X355000Y1751250D02*
Y1747750D01*
G01D02*
X355250Y1747500D01*
G01X354000Y1742500D02*
X355250Y1743750D01*
G01D02*
Y1747500D01*
G01X351000Y1731000D02*
Y1739500D01*
G01D02*
X354000Y1742500D01*
G01X347000Y1754750D02*
Y1758750D01*
G01D02*
X347250Y1759000D01*
G01Y1764000D02*
Y1759000D01*
G01Y1764000D02*
Y1786063D01*
G01X406000Y399000D02*
Y402500D01*
G01X404000Y392000D02*
X406000Y394000D01*
G01D02*
Y399000D01*
G01X447876Y647364D02*
X489565Y605675D01*
G01X445701Y646463D02*
X488664Y603500D01*
G01X447876Y813124D02*
Y647364D01*
G01X445701Y797449D02*
Y646463D01*
G01X421250Y809500D02*
X417750D01*
G01D02*
X417500Y809250D01*
G01X412500Y810500D02*
X413750Y809250D01*
G01D02*
X417500D01*
G01X412500Y810500D02*
X410000Y813000D01*
G01X424750Y817500D02*
X428750D01*
G01D02*
X429000Y817250D01*
G01X434000D02*
X429000D01*
G01X434000D02*
X443750D01*
G01D02*
X447876Y813124D01*
G01X424750Y809500D02*
X428750D01*
G01D02*
X429000Y809250D01*
G01X433900D02*
X429000D01*
G01X433900D02*
X445701Y797449D01*
G01X421250Y817500D02*
X421000Y817250D01*
G01D02*
X417500D01*
G01X410175Y815675D02*
X411750Y817250D01*
G01D02*
X417500D01*
G01X420722Y820627D02*
X421250Y820099D01*
G01D02*
Y817500D01*
G01X417750Y1212000D02*
X417500Y1211750D01*
G01X412500Y1213000D02*
X413750Y1211750D01*
G01X428750Y1212000D02*
X429000Y1211750D01*
G01X421250Y1220000D02*
X417750D01*
G01D02*
X417500Y1219750D01*
G01X420763Y1223185D02*
X421250Y1222698D01*
G01D02*
Y1220000D01*
G01X417500Y1219750D02*
X411750D01*
G01D02*
X408675Y1216675D01*
G01X424750Y1220000D02*
X428750D01*
G01D02*
X429000Y1219750D01*
G01X434000D02*
X509674D01*
G01X434000D02*
X429000D01*
G01X421250Y1212000D02*
X417750D01*
G01X413750Y1211750D02*
X417500D01*
G01X412500Y1213000D02*
X411000Y1214500D01*
G01X424750Y1212000D02*
X428750D01*
G01X433900Y1211750D02*
X429000D01*
G01X433900D02*
X504750D01*
G01X701863Y1717939D02*
X434311D01*
G01D02*
X434000Y1718250D01*
G01X424750Y1718500D02*
X428750D01*
G01D02*
X429000Y1718250D01*
G01X434000D02*
X429000D01*
G01X421250Y1718500D02*
X421000Y1718250D01*
G01D02*
X417500D01*
G01X421250Y1721239D02*
Y1718500D01*
G01X417500Y1718250D02*
X412600D01*
G01D02*
X409525Y1715175D01*
G01X424750Y1710500D02*
X428750D01*
G01D02*
X429000Y1710250D01*
G01X433900D02*
X429000D01*
G01X702764Y1715764D02*
X449062D01*
G01D02*
X443548Y1710250D01*
G01D02*
X433900D01*
G01X421250Y1710500D02*
X417750D01*
G01D02*
X417500Y1710250D01*
G01X411000Y1713000D02*
X412500Y1711500D01*
G01D02*
X413750Y1710250D01*
G01D02*
X417500D01*
G01X420732Y1721757D02*
X421250Y1721239D01*
G01X489565Y605675D02*
X903599D01*
G01X488664Y603500D02*
X904500D01*
G01X490500Y1011500D02*
X901400D01*
G01X489599Y1009325D02*
X906901D01*
G01X504750Y1211750D02*
X708000Y1415000D01*
G01X509674Y1219750D02*
X707099Y1417175D01*
G01D02*
X901875D01*
G01X708000Y1415000D02*
X905500D01*
G01X754924Y1771000D02*
X701863Y1717939D01*
G01X755500Y1768500D02*
X702764Y1715764D01*
G01X842755Y1771000D02*
X754924D01*
G01X845600Y1768500D02*
X755500D01*
G01X760164Y1968282D02*
Y1964582D01*
G01D02*
X761489Y1963257D01*
G01D02*
X764739D01*
G01X755995Y1968282D02*
X760164D01*
G01X769239Y1963257D02*
X764739D01*
G01X763664Y1968282D02*
X768564D01*
G01X820650Y191633D02*
X815633D01*
G01D02*
X810500Y186500D01*
G01D02*
Y183000D01*
G01X828500D02*
Y186500D01*
G01D02*
X833633Y191633D01*
G01D02*
X836830D01*
G01X828500Y177750D02*
Y183000D01*
G01Y177750D02*
X824500D01*
G01X836500Y183000D02*
Y184500D01*
G01D02*
X836830Y184830D01*
G01D02*
Y189073D01*
G01X832500Y177750D02*
X836500D01*
G01D02*
Y183000D01*
G01X820500D02*
Y177750D01*
G01X816500D02*
X820500D01*
G01X831693Y194193D02*
X820500Y183000D01*
G01X836830Y194193D02*
X831693D01*
G01X827875Y362750D02*
Y365375D01*
G01D02*
X830000Y367500D01*
G01D02*
Y372000D01*
G01D02*
X829250Y372750D01*
G01D02*
X821000D01*
G01D02*
X816500D01*
G01X807756Y377775D02*
X811925D01*
G01D02*
Y375701D01*
G01D02*
X814876Y372750D01*
G01D02*
X816500D01*
G01X840150Y373900D02*
X834250D01*
G01X815425Y377775D02*
X820325D01*
G01X826750D02*
X820325D01*
G01X813000Y357000D02*
X822250D01*
G01D02*
X824000Y355250D01*
G01X824250Y349000D02*
Y355000D01*
G01D02*
X824000Y355250D01*
G01X819500Y344750D02*
X819000Y345250D01*
G01D02*
Y349600D01*
G01D02*
X821400D01*
G01D02*
X822000Y349000D01*
G01D02*
X824250D01*
G01X813000Y348000D02*
Y342500D01*
G01D02*
X814250Y341250D01*
G01X824000D02*
X828000D01*
G01X819500D02*
X814250D01*
G01X819500D02*
X824000D01*
G01X828000D02*
X830050D01*
G01D02*
X831300Y342500D01*
G01D02*
X835500D01*
G01X813000Y762500D02*
X822250D01*
G01D02*
X824000Y760750D01*
G01X824250Y754500D02*
Y760500D01*
G01D02*
X824000Y760750D01*
G01X819500Y750250D02*
X819000Y750750D01*
G01D02*
Y755100D01*
G01D02*
X821400D01*
G01D02*
X822000Y754500D01*
G01D02*
X824250D01*
G01X827875Y768250D02*
Y770625D01*
G01D02*
X830500Y773250D01*
G01D02*
Y777000D01*
G01X813000Y753500D02*
Y748000D01*
G01D02*
X814250Y746750D01*
G01X828000D02*
X830050D01*
G01D02*
X831300Y748000D01*
G01D02*
X835500D01*
G01X819500Y746750D02*
X814250D01*
G01X819500D02*
X824000D01*
G01D02*
X828000D01*
G01X815425Y783275D02*
X820325D01*
G01X826750D02*
X820325D01*
G01X840150Y779400D02*
X834250D01*
G01X808256Y783275D02*
X811925D01*
G01X830500Y777000D02*
X829250Y778250D01*
G01D02*
X821000D01*
G01D02*
X816500D01*
G01X811925Y783275D02*
Y781201D01*
G01D02*
X814876Y778250D01*
G01D02*
X816500D01*
G01X821000Y1183750D02*
X816500D01*
G01X807756Y1188775D02*
X811925D01*
G01X816500Y1183750D02*
X814876D01*
G01D02*
X811925Y1186701D01*
G01D02*
Y1188775D01*
G01X827875Y1173750D02*
X830000Y1175875D01*
G01D02*
Y1182500D01*
G01D02*
X828750Y1183750D01*
G01D02*
X821000D01*
G01X813000Y1159000D02*
Y1153500D01*
G01D02*
X814250Y1152250D01*
G01X828000D02*
X830050D01*
G01D02*
X831300Y1153500D01*
G01D02*
X835500D01*
G01X819500Y1152250D02*
X814250D01*
G01X819500D02*
X824000D01*
G01D02*
X828000D01*
G01X840150Y1184900D02*
X834250D01*
G01X813000Y1168000D02*
X822250D01*
G01D02*
X824000Y1166250D01*
G01X824250Y1160000D02*
Y1166000D01*
G01D02*
X824000Y1166250D01*
G01X819500Y1155750D02*
X819000Y1156250D01*
G01D02*
Y1160600D01*
G01D02*
X821400D01*
G01D02*
X822000Y1160000D01*
G01D02*
X824250D01*
G01X815425Y1188775D02*
X820325D01*
G01X826750D02*
X820325D01*
G01X813000Y1564500D02*
Y1559000D01*
G01D02*
X814250Y1557750D01*
G01X824000D02*
X828000D01*
G01X819500D02*
X814250D01*
G01X819500D02*
X824000D01*
G01X828000D02*
X829950D01*
G01D02*
X831200Y1559000D01*
G01D02*
X835500D01*
G01X813000Y1573500D02*
X822250D01*
G01D02*
X824000Y1571750D01*
G01X819500Y1561250D02*
X819200Y1561550D01*
G01D02*
Y1566100D01*
G01X824250Y1565500D02*
Y1571500D01*
G01D02*
X824000Y1571750D01*
G01X824250Y1565500D02*
X822400D01*
G01D02*
X821400Y1566500D01*
G01D02*
X819600D01*
G01D02*
X819200Y1566100D01*
G01X821000Y1589250D02*
X816500D01*
G01X807756Y1594275D02*
X811925D01*
G01X827875Y1579250D02*
Y1581875D01*
G01D02*
X830000Y1584000D01*
G01D02*
Y1588000D01*
G01D02*
X828750Y1589250D01*
G01D02*
X821000D01*
G01X816500D02*
X814876D01*
G01D02*
X811925Y1592201D01*
G01D02*
Y1594275D01*
G01X815425D02*
X820325D01*
G01X826750D02*
X820325D01*
G01X840150Y1590400D02*
X834250D01*
G01X829500Y1791750D02*
Y1797000D01*
G01Y1791750D02*
X825500D01*
G01X837500Y1797000D02*
Y1791750D01*
G01X841500D02*
X837500D01*
G01X819000Y1797000D02*
Y1791750D01*
G01X815000D02*
X819000D01*
G01X829500Y1797000D02*
Y1801500D01*
G01D02*
X833807Y1805807D01*
G01D02*
X836830D01*
G01Y1803247D02*
Y1797670D01*
G01D02*
X837500Y1797000D01*
G01X820650Y1805807D02*
X815807D01*
G01D02*
X810500Y1800500D01*
G01D02*
Y1797000D01*
G01X836830Y1808367D02*
X831867D01*
G01D02*
X823750Y1800250D01*
G01D02*
X822250D01*
G01D02*
X819000Y1797000D01*
G01X802439Y1934107D02*
X797639D01*
G01D02*
X795289Y1931757D01*
G01D02*
X792839D01*
G01X779089D02*
X784339D01*
G01X777839Y1938507D02*
Y1933007D01*
G01D02*
X779089Y1931757D01*
G01X784339D02*
X788839D01*
G01D02*
X792839D01*
G01X783939Y1940107D02*
Y1935657D01*
G01D02*
X784339Y1935257D01*
G01X792714Y1953257D02*
Y1956132D01*
G01D02*
X791339Y1957507D01*
G01D02*
X783639D01*
G01D02*
X777889Y1963257D01*
G01D02*
X769239D01*
G01X777839Y1947507D02*
X787089D01*
G01D02*
X788839Y1945757D01*
G01X783939Y1940107D02*
X786239D01*
G01D02*
X786839Y1939507D01*
G01D02*
X789089D01*
G01D02*
Y1945507D01*
G01D02*
X788839Y1945757D01*
G01X774989Y1968282D02*
X768564D01*
G01X794489D02*
X793485Y1969286D01*
G01D02*
X788389D01*
G01Y1964407D02*
X782489D01*
G01X788389D02*
Y1969286D01*
G01X909881Y131990D02*
X913313D01*
G01X909881D02*
X905748D01*
G01D02*
X902845Y134893D01*
G01D02*
X898750D01*
G01X898725Y154724D02*
X908876D01*
G01D02*
X910098Y153502D01*
G01D02*
X915037D01*
G01X896731Y160211D02*
Y156718D01*
G01D02*
X898725Y154724D01*
G01X909733Y158953D02*
X914447D01*
G01X902481Y160211D02*
X905000D01*
G01D02*
X906258Y158953D01*
G01D02*
X909733D01*
G01X896731Y163411D02*
X894089D01*
G01D02*
X893000Y164500D01*
G01D02*
Y165920D01*
G01D02*
X890566Y168354D01*
G01X879000Y169500D02*
X880693Y171193D01*
G01D02*
X888241D01*
G01D02*
X890566Y168868D01*
G01D02*
Y168354D01*
G01X876161Y163411D02*
Y166661D01*
G01D02*
X879000Y169500D01*
G01X910750Y141223D02*
Y138573D01*
G01D02*
X911744Y137579D01*
G01D02*
X915126D01*
G01X910750Y141223D02*
Y146453D01*
G01X889750Y157000D02*
Y148886D01*
G01D02*
X893768Y144868D01*
G01D02*
Y143505D01*
G01D02*
X895500Y141773D01*
G01D02*
Y138619D01*
G01D02*
X894334Y137453D01*
G01D02*
X892250D01*
G01X889750Y157000D02*
Y161000D01*
G01D02*
Y164085D01*
G01D02*
X890469Y164804D01*
G01X902481Y163411D02*
X905000D01*
G01D02*
X906042Y164453D01*
G01D02*
X914833D01*
G01X869250Y148875D02*
X864975D01*
G01X884000Y140013D02*
X881737D01*
G01D02*
X876750Y145000D01*
G01X892250Y140013D02*
X884000D01*
G01X876750Y145000D02*
Y151447D01*
G01D02*
X872286Y155911D01*
G01D02*
X866961D01*
G01X880036D02*
Y149964D01*
G01D02*
X881000Y149000D01*
G01D02*
X883412D01*
G01D02*
X885000D01*
G01D02*
X886250Y150250D01*
G01D02*
Y157000D01*
G01X904728Y151181D02*
X902580D01*
G01D02*
X902102Y150703D01*
G01D02*
X899648D01*
G01D02*
X896647D01*
G01D02*
X896547Y150803D01*
G01X904728Y151181D02*
X906250D01*
G01D02*
X907250Y150181D01*
G01D02*
Y146453D01*
G01X895236Y247992D02*
X899792D01*
G01D02*
X901600Y249800D01*
G01X895236Y251141D02*
X900259D01*
G01D02*
X901600Y249800D01*
G01X860368Y198000D02*
X904500D01*
G01D02*
X914500Y208000D01*
G01X861269Y200175D02*
X903599D01*
G01D02*
X912325Y208901D01*
G01Y261533D02*
X899941Y273917D01*
G01X914500Y289358D02*
X899941Y303917D01*
G01D02*
X893602D01*
G01X899941Y273917D02*
X893602D01*
G01Y308917D02*
X899941D01*
G01X850125Y330750D02*
X856200D01*
G01D02*
X857450Y329500D01*
G01D02*
X870500D01*
G01D02*
X871693Y328307D01*
G01D02*
X882677D01*
G01X844050Y330750D02*
X850125D01*
G01X840150Y373900D02*
Y378779D01*
G01D02*
X845246D01*
G01D02*
X846250Y377775D01*
G01X884500Y556715D02*
Y549965D01*
G01D02*
X883500Y548965D01*
G01D02*
X881500D01*
G01D02*
X879500D01*
G01D02*
X878375Y550090D01*
G01D02*
Y555715D01*
G01X914675Y536837D02*
X907492D01*
G01D02*
X905413D01*
G01D02*
X901845Y540405D01*
G01D02*
X897750D01*
G01X909750Y551965D02*
Y546735D01*
G01X915126Y543091D02*
X910744D01*
G01D02*
X909750Y544085D01*
G01D02*
Y546735D01*
G01X865125Y539715D02*
Y544000D01*
G01X880636Y541514D02*
X883549D01*
G01D02*
X887560Y545525D01*
G01D02*
X891250D01*
G01X870625Y555715D02*
X867500D01*
G01D02*
X865250Y553465D01*
G01X870625Y555715D02*
Y552090D01*
G01D02*
X869000Y550465D01*
G01D02*
Y547215D01*
G01D02*
X872500D01*
G01D02*
X878201Y541514D01*
G01D02*
X880636D01*
G01X903728Y556693D02*
X901457D01*
G01D02*
X900979Y556215D01*
G01D02*
X898754D01*
G01D02*
X895647D01*
G01D02*
X895547Y556315D01*
G01X903728Y556693D02*
X905498D01*
G01D02*
X906250Y555941D01*
G01D02*
Y551965D01*
G01X894500Y547800D02*
Y547988D01*
G01D02*
X888000Y554488D01*
G01D02*
Y556715D01*
G01D02*
Y560715D01*
G01X894500Y547800D02*
Y543965D01*
G01D02*
X893500Y542965D01*
G01D02*
X891250D01*
G01X903599Y605675D02*
X912937Y615013D01*
G01X909733Y564465D02*
X914135D01*
G01X902481Y565723D02*
X905500D01*
G01D02*
X906758Y564465D01*
G01D02*
X909733D01*
G01X904500Y603500D02*
X915112Y614112D01*
G01X902481Y568923D02*
X905000D01*
G01D02*
X906042Y569965D01*
G01D02*
X914833D01*
G01X895926Y574422D02*
X892342D01*
G01D02*
X886843Y568923D01*
G01X896731D02*
Y573617D01*
G01D02*
X895926Y574422D01*
G01X886843Y568923D02*
X876958D01*
G01D02*
X874500Y566465D01*
G01D02*
Y563215D01*
G01X896991Y560408D02*
X907092D01*
G01D02*
X908486Y559014D01*
G01D02*
X914186D01*
G01X896731Y565723D02*
Y560668D01*
G01D02*
X896991Y560408D01*
G01X888000Y560715D02*
Y563800D01*
G01D02*
X888719Y564519D01*
G01X912937Y666433D02*
X899941Y679429D01*
G01D02*
X893602D01*
G01X915112Y694258D02*
X899941Y709429D01*
G01X895236Y653504D02*
X899604D01*
G01D02*
X901200Y655100D01*
G01X895236Y656653D02*
X899647D01*
G01D02*
X901200Y655100D01*
G01X899941Y709429D02*
X893602D01*
G01X851150Y736750D02*
X856100D01*
G01X851150D02*
X846200D01*
G01X856100D02*
X857350D01*
G01D02*
X858900Y735200D01*
G01D02*
X867200D01*
G01D02*
X868581Y733819D01*
G01D02*
X882677D01*
G01X893602Y714429D02*
X899941D01*
G01X840150Y779400D02*
Y784279D01*
G01D02*
X845246D01*
G01D02*
X846250Y783275D01*
G01X909733Y969977D02*
X913023D01*
G01X902481Y971235D02*
X905500D01*
G01D02*
X906758Y969977D01*
G01D02*
X909733D01*
G01X898648Y961727D02*
X901167D01*
G01D02*
X901645Y962205D01*
G01D02*
X903728D01*
G01D02*
X905250D01*
G01D02*
X906250Y961205D01*
G01D02*
Y957477D01*
G01X898648Y961727D02*
X895647D01*
G01D02*
X895547Y961827D01*
G01X912177Y942729D02*
X908177D01*
G01D02*
X905033D01*
G01D02*
X901845Y945917D01*
G01D02*
X897750D01*
G01X909750Y957477D02*
Y952247D01*
G01X915126Y948603D02*
X910744D01*
G01D02*
X909750Y949597D01*
G01D02*
Y952247D01*
G01X889909Y977357D02*
X891522D01*
G01D02*
X894444Y974435D01*
G01D02*
X896731D01*
G01X889909Y977357D02*
X881357D01*
G01D02*
X879800Y975800D01*
G01D02*
X878323D01*
G01D02*
X874500Y971977D01*
G01D02*
Y968727D01*
G01X891250Y948477D02*
X893500D01*
G01D02*
X894500Y949477D01*
G01D02*
Y953500D01*
G01D02*
X890550Y957450D01*
G01X888000Y962227D02*
Y960000D01*
G01D02*
X890550Y957450D01*
G01X888000Y966227D02*
Y962227D01*
G01Y966227D02*
Y969312D01*
G01D02*
X888719Y970031D01*
G01X884500Y962227D02*
Y955477D01*
G01D02*
X883500Y954477D01*
G01D02*
X881500D01*
G01D02*
X879500D01*
G01D02*
X878375Y955602D01*
G01D02*
Y961227D01*
G01X902481Y974435D02*
X905500D01*
G01D02*
X906542Y975477D01*
G01D02*
X914833D01*
G01X865125Y949600D02*
Y945227D01*
G01X897224Y965913D02*
X906787D01*
G01D02*
X908486Y964214D01*
G01D02*
X914646D01*
G01X896731Y971235D02*
Y966406D01*
G01D02*
X897224Y965913D01*
G01X880636Y947026D02*
X883549D01*
G01D02*
X887560Y951037D01*
G01D02*
X891250D01*
G01X869000Y952727D02*
X872500D01*
G01D02*
X878201Y947026D01*
G01D02*
X880636D01*
G01X870625Y961227D02*
X867500D01*
G01D02*
X865250Y958977D01*
G01X870625Y961227D02*
Y957602D01*
G01D02*
X869000Y955977D01*
G01D02*
Y952727D01*
G01X901400Y1011500D02*
X904600Y1014700D01*
G01D02*
X909200D01*
G01D02*
X912937Y1018437D01*
G01X895236Y1059016D02*
X899616D01*
G01D02*
X901300Y1060700D01*
G01X895236Y1062165D02*
X899835D01*
G01D02*
X901300Y1060700D01*
G01X906901Y1009325D02*
X915112Y1017536D01*
G01X893602Y1119941D02*
X899941D01*
G01X912937Y1071945D02*
X899941Y1084941D01*
G01D02*
X893602D01*
G01X915112Y1099770D02*
X899941Y1114941D01*
G01D02*
X893602D01*
G01X854500Y1142150D02*
X849550D01*
G01D02*
X844600D01*
G01X854500D02*
X857350D01*
G01D02*
X859000Y1140500D01*
G01D02*
X867231D01*
G01D02*
X868400Y1139331D01*
G01D02*
X882677D01*
G01X840150Y1184900D02*
Y1189779D01*
G01D02*
X845246D01*
G01D02*
X846250Y1188775D01*
G01X865125Y1350738D02*
Y1346488D01*
G01X891250Y1353988D02*
X893688D01*
G01D02*
X894500Y1354800D01*
G01D02*
Y1360500D01*
G01X908530Y1348458D02*
X913142D01*
G01X908530D02*
X903542D01*
G01D02*
X900572Y1351428D01*
G01D02*
X897750D01*
G01X915126Y1354114D02*
X910744D01*
G01D02*
X909750Y1355108D01*
G01D02*
Y1357758D01*
G01X880636Y1352537D02*
X883549D01*
G01D02*
X887560Y1356548D01*
G01D02*
X891250D01*
G01X872250Y1358238D02*
X877951Y1352537D01*
G01D02*
X880636D01*
G01X902481Y1379946D02*
X905446D01*
G01D02*
X906488Y1380988D01*
G01D02*
X914833D01*
G01X898748Y1367238D02*
X895747D01*
G01D02*
X895647Y1367338D01*
G01X898748Y1367238D02*
X901500D01*
G01D02*
X901921Y1367659D01*
G01D02*
X903900D01*
G01D02*
X905241D01*
G01D02*
X906250Y1366650D01*
G01D02*
Y1362988D01*
G01X887438Y1373374D02*
Y1369700D01*
G01D02*
Y1365200D01*
G01X894500Y1360500D02*
X893438Y1361562D01*
G01D02*
X893395D01*
G01D02*
X889970Y1364987D01*
G01D02*
Y1365030D01*
G01D02*
X889800Y1365200D01*
G01D02*
X887438D01*
G01X890213Y1379946D02*
X896731D01*
G01X880100Y1380100D02*
X880254Y1379946D01*
G01D02*
X890213D01*
G01X880100Y1380100D02*
X879946Y1379946D01*
G01D02*
X876958D01*
G01D02*
X874500Y1377488D01*
G01D02*
Y1374238D01*
G01X883938Y1365200D02*
Y1360426D01*
G01D02*
X883500Y1359988D01*
G01D02*
X881500D01*
G01D02*
X879500D01*
G01D02*
X878375Y1361113D01*
G01D02*
Y1366738D01*
G01X914012Y1375488D02*
X909733D01*
G01X902481Y1376746D02*
X905500D01*
G01D02*
X906758Y1375488D01*
G01D02*
X909733D01*
G01X909750Y1362988D02*
Y1357758D01*
G01X901875Y1417175D02*
X912937Y1428237D01*
G01X915037Y1370037D02*
X898149D01*
G01D02*
X896835Y1371351D01*
G01X896731Y1376746D02*
Y1371455D01*
G01D02*
X896835Y1371351D01*
G01X870625Y1366738D02*
Y1363113D01*
G01D02*
X869000Y1361488D01*
G01D02*
Y1358238D01*
G01X870625Y1366738D02*
X867500D01*
G01D02*
X865250Y1364488D01*
G01X869000Y1358238D02*
X872250D01*
G01X905500Y1415000D02*
X915112Y1424612D01*
G01X895236Y1467677D02*
X899823D01*
G01D02*
X901400Y1466100D01*
G01X895236Y1464528D02*
X899828D01*
G01D02*
X901400Y1466100D01*
G01X912937Y1477457D02*
X899941Y1490453D01*
G01D02*
X893602D01*
G01X850550Y1547750D02*
X845600D01*
G01X855500D02*
X850550D01*
G01X855500D02*
X857250Y1546000D01*
G01D02*
X867000D01*
G01D02*
X868157Y1544843D01*
G01D02*
X882677D01*
G01X893602Y1525453D02*
X899941D01*
G01X915112Y1505282D02*
X899941Y1520453D01*
G01D02*
X893602D01*
G01X840150Y1590400D02*
Y1595279D01*
G01D02*
X845246D01*
G01D02*
X846250Y1594275D01*
G01X869282Y1797527D02*
X842755Y1771000D01*
G01X888000Y1773250D02*
Y1777250D01*
G01X891250Y1759500D02*
X893500D01*
G01D02*
X894500Y1760500D01*
G01D02*
Y1764819D01*
G01D02*
X888000Y1771319D01*
G01D02*
Y1773250D01*
G01Y1777250D02*
Y1780335D01*
G01D02*
X888719Y1781054D01*
G01X881500Y1765500D02*
X879500D01*
G01D02*
X878375Y1766625D01*
G01D02*
Y1772250D01*
G01X884500Y1773250D02*
Y1766500D01*
G01D02*
X883500Y1765500D01*
G01D02*
X881500D01*
G01X896731Y1782258D02*
Y1779757D01*
G01D02*
X897150Y1779338D01*
G01D02*
Y1776900D01*
G01X913184Y1776716D02*
X897334D01*
G01D02*
X897150Y1776900D01*
G01X898800Y1772750D02*
X895647D01*
G01D02*
X895547Y1772850D01*
G01X898800Y1772750D02*
X901522D01*
G01D02*
X902000Y1773228D01*
G01D02*
X903728D01*
G01D02*
X905250D01*
G01D02*
X906250Y1772228D01*
G01D02*
Y1768500D01*
G01X865125Y1756250D02*
Y1751800D01*
G01X897750Y1756940D02*
X901329D01*
G01D02*
X906269Y1752000D01*
G01D02*
X913923D01*
G01X871457Y1794357D02*
X845600Y1768500D01*
G01X896731Y1785458D02*
Y1789527D01*
G01D02*
X895442Y1790816D01*
G01D02*
X892428D01*
G01D02*
X887070Y1785458D01*
G01D02*
X886843D01*
G01D02*
X876958D01*
G01D02*
X874500Y1783000D01*
G01D02*
Y1779750D01*
G01X902481Y1785458D02*
X905958D01*
G01D02*
X907000Y1786500D01*
G01D02*
X914833D01*
G01X909750Y1768500D02*
Y1763270D01*
G01D02*
Y1760871D01*
G01D02*
X910995Y1759626D01*
G01D02*
X915126D01*
G01X902481Y1782258D02*
X906000D01*
G01D02*
X907258Y1781000D01*
G01D02*
X909733D01*
G01X914100D02*
X909733D01*
G01X881636Y1757549D02*
X878251D01*
G01D02*
X872050Y1763750D01*
G01D02*
X869000D01*
G01X870625Y1772250D02*
X867500D01*
G01D02*
X865250Y1770000D01*
G01X870625Y1772250D02*
Y1768425D01*
G01D02*
X869000Y1766800D01*
G01D02*
Y1763750D01*
G01X891250Y1762060D02*
X887560D01*
G01D02*
X883049Y1757549D01*
G01D02*
X881636D01*
G01X912325Y1829825D02*
X904500Y1822000D01*
G01D02*
X875000D01*
G01D02*
X869282Y1816282D01*
G01D02*
Y1797527D01*
G01X914500Y1828924D02*
X905401Y1819825D01*
G01D02*
X875901D01*
G01D02*
X871457Y1815381D01*
G01D02*
Y1794357D01*
G01X893602Y1895965D02*
X899941D01*
G01D02*
X912325Y1883581D01*
G01X895236Y1870040D02*
X899640D01*
G01D02*
X901200Y1871600D01*
G01X895236Y1873189D02*
X899611D01*
G01D02*
X901200Y1871600D01*
G01X893602Y1930965D02*
X899941D01*
G01X893602Y1925965D02*
X899941D01*
G01D02*
X914500Y1911406D01*
G01X856900Y1947600D02*
X859800Y1944700D01*
G01D02*
X868248D01*
G01D02*
X872448Y1948900D01*
G01D02*
X875900D01*
G01D02*
X877354Y1950354D01*
G01D02*
X882676D01*
G01D02*
X882677Y1950355D01*
G01X851350Y1949700D02*
X854800D01*
G01D02*
X856900Y1947600D01*
G01X851350Y1945200D02*
Y1949700D01*
G01X913313Y131990D02*
X915350Y129953D01*
G01D02*
X919750D01*
G01X920500Y137203D02*
Y150000D01*
G01D02*
X916998Y153502D01*
G01D02*
X915037D01*
G01X914447Y158953D02*
X917900Y155500D01*
G01D02*
X919750D01*
G01Y160000D02*
Y155500D01*
G01X915126Y137579D02*
X916625Y139078D01*
G01D02*
Y144703D01*
G01X919750Y164453D02*
X914833D01*
G01X923250Y129953D02*
X927500D01*
G01D02*
X931500Y133953D01*
G01D02*
Y139453D01*
G01D02*
Y142453D01*
G01D02*
X929250Y144703D01*
G01D02*
X924375D01*
G01X914500Y208000D02*
Y289358D01*
G01X912325Y208901D02*
Y261533D01*
G01X919750Y535465D02*
X916047D01*
G01D02*
X914675Y536837D01*
G01X916625Y550215D02*
Y544590D01*
G01D02*
X915126Y543091D01*
G01X923250Y535465D02*
X927500D01*
G01D02*
X931500Y539465D01*
G01D02*
Y544965D01*
G01D02*
Y547965D01*
G01D02*
X929250Y550215D01*
G01D02*
X924375D01*
G01X914186Y559014D02*
X916600Y556600D01*
G01X920500Y542715D02*
Y552700D01*
G01D02*
X916600Y556600D01*
G01X912937Y615013D02*
Y666433D01*
G01X914135Y564465D02*
X917600Y561000D01*
G01D02*
X919750D01*
G01D02*
Y565500D01*
G01X915112Y614112D02*
Y694258D01*
G01X919750Y569965D02*
X914833D01*
G01X923250Y940977D02*
X927500D01*
G01D02*
X931500Y944977D01*
G01D02*
Y950477D01*
G01D02*
Y953477D01*
G01D02*
X929250Y955727D01*
G01D02*
X924375D01*
G01X913023Y969977D02*
X916500Y966500D01*
G01D02*
X919750D01*
G01Y971000D02*
Y966500D01*
G01Y940977D02*
X913929D01*
G01D02*
X912177Y942729D01*
G01X916625Y955727D02*
Y950102D01*
G01D02*
X915126Y948603D01*
G01X919750Y975477D02*
X914833D01*
G01X914646Y964214D02*
X918286D01*
G01D02*
X920500Y962000D01*
G01D02*
Y948227D01*
G01X912937Y1018437D02*
Y1071945D01*
G01X915112Y1017536D02*
Y1099770D01*
G01X913142Y1348458D02*
X915112Y1346488D01*
G01D02*
X919750D01*
G01X923250D02*
X927500D01*
G01D02*
X931500Y1350488D01*
G01D02*
Y1355988D01*
G01D02*
Y1358988D01*
G01X916625Y1361238D02*
Y1355613D01*
G01D02*
X915126Y1354114D01*
G01X920500Y1353738D02*
Y1365800D01*
G01X919750Y1380988D02*
X914833D01*
G01X931500Y1358988D02*
X929250Y1361238D01*
G01D02*
X924375D01*
G01X919750Y1372000D02*
X917500D01*
G01D02*
X914012Y1375488D01*
G01X919750Y1376500D02*
Y1372000D01*
G01X912937Y1428237D02*
Y1477457D01*
G01X920500Y1365800D02*
X916263Y1370037D01*
G01D02*
X915037D01*
G01X915112Y1424612D02*
Y1505282D01*
G01X926500Y1660000D02*
X942500Y1644000D01*
G01D02*
X992000D01*
G01X943500Y1646989D02*
X982989D01*
G01D02*
X987102Y1651102D01*
G01X969000Y1641500D02*
X973000D01*
G01X976000Y1636000D02*
X979500Y1639500D01*
G01D02*
X993000D01*
G01X985898Y1668602D02*
X978000Y1676500D01*
G01D02*
X969500D01*
G01X931000Y1659000D02*
X938500D01*
G01D02*
X945500Y1652000D01*
G01D02*
X984500D01*
G01D02*
X986500Y1654000D01*
G01X934825Y1682285D02*
X975715D01*
G01D02*
X986898Y1671102D01*
G01X947000Y1654500D02*
X983500D01*
G01D02*
X990102Y1661102D01*
G01X923250Y1752000D02*
X927500D01*
G01D02*
X931500Y1756000D01*
G01D02*
Y1761500D01*
G01X924375Y1766750D02*
X929250D01*
G01D02*
X931500Y1764500D01*
G01D02*
Y1761500D01*
G01X916100Y1773800D02*
X913184Y1776716D01*
G01X920500Y1759250D02*
Y1769400D01*
G01D02*
X916100Y1773800D01*
G01X913923Y1752000D02*
X919750D01*
G01Y1786500D02*
X914833D01*
G01X915126Y1759626D02*
X916625Y1761125D01*
G01D02*
Y1766750D01*
G01X919750Y1777500D02*
X917600D01*
G01D02*
X914100Y1781000D01*
G01X919750Y1782000D02*
Y1777500D01*
G01X912325Y1883581D02*
Y1829825D01*
G01X914500Y1911406D02*
Y1828924D01*
G01X992000Y1644000D02*
X994898Y1641102D01*
G01D02*
X1009744D01*
G01X993000Y1639500D02*
X996398Y1636102D01*
G01D02*
X1009744D01*
G01Y1666102D02*
X999398D01*
G01D02*
X996898Y1668602D01*
G01D02*
X985898D01*
G01X986500Y1654000D02*
X997500D01*
G01D02*
X999602Y1656102D01*
G01D02*
X1009744D01*
G01X986898Y1671102D02*
X1009744D01*
G01X990102Y1661102D02*
X1009744D01*
G01X987102Y1651102D02*
X1009744D01*
M02*
